FILE_TYPE = MACRO_DRAWING;
SET COLOR_WIRE YELLOW;
SET COLOR_PROP ORANGE;
SET COLOR_DOT WHITE;
SET COLOR_ARC YELLOW;
SET COLOR_BODY GREEN;
SET COLOR_NOTE PURPLE;
SET PROP_DISPLAY VALUE;
SET PAGE_NUMBER P32;
FORCEADD TAP..1
R 2
(-400 2725);
FORCEPROP 3 LASTPIN (-350 2725) SIG_NAME UPI_CPU1_CPU0_P1P0_DP<4>
J 0
(-340 2735);
DISPLAY 0.659574 (-340 2735);
PAINT MONO (-340 2735);
DISPLAY INVISIBLE (-340 2735);
FORCEPROP 1 LASTPIN (-350 2725) BN 4
J 2
(-338 2733);
DISPLAY 0.680851 (-338 2733);
PAINT GREEN (-338 2733);
FORCEPROP 2 LAST CDS_LIB standard
J 0
(-400 2725);
DISPLAY INVISIBLE (-400 2725);
FORCEPROP 1 LAST BODY_TYPE PLUMBING
J 2
(-400 2775);
DISPLAY 0.872340 (-400 2775);
PAINT GREEN (-400 2775);
DISPLAY INVISIBLE (-400 2775);
FORCEPROP 1 LAST HDL_TAP TRUE
J 2
(-725 2600);
DISPLAY 0.872340 (-725 2600);
DISPLAY INVISIBLE (-725 2600);
FORCEPROP 1 LAST PATH I101
J 2
(-398 2725);
DISPLAY 0.872340 (-398 2725);
PAINT GREEN (-398 2725);
DISPLAY INVISIBLE (-398 2725);
FORCEADD TAP..1
R 2
(-400 2525);
FORCEPROP 3 LASTPIN (-350 2525) SIG_NAME UPI_CPU1_CPU0_P1P0_DP<0>
J 0
(-340 2535);
DISPLAY 0.659574 (-340 2535);
PAINT MONO (-340 2535);
DISPLAY INVISIBLE (-340 2535);
FORCEPROP 1 LASTPIN (-350 2525) BN 0
J 2
(-338 2533);
DISPLAY 0.680851 (-338 2533);
PAINT GREEN (-338 2533);
FORCEPROP 2 LAST CDS_LIB standard
J 0
(-400 2525);
DISPLAY INVISIBLE (-400 2525);
FORCEPROP 1 LAST BODY_TYPE PLUMBING
J 2
(-400 2575);
DISPLAY 0.872340 (-400 2575);
PAINT GREEN (-400 2575);
DISPLAY INVISIBLE (-400 2575);
FORCEPROP 1 LAST HDL_TAP TRUE
J 2
(-725 2400);
DISPLAY 0.872340 (-725 2400);
DISPLAY INVISIBLE (-725 2400);
FORCEPROP 1 LAST PATH I102
J 2
(-398 2525);
DISPLAY 0.872340 (-398 2525);
PAINT GREEN (-398 2525);
DISPLAY INVISIBLE (-398 2525);
FORCEADD TAP..1
R 2
(-400 2825);
FORCEPROP 3 LASTPIN (-350 2825) SIG_NAME UPI_CPU1_CPU0_P1P0_DP<6>
J 0
(-340 2835);
DISPLAY 0.659574 (-340 2835);
PAINT MONO (-340 2835);
DISPLAY INVISIBLE (-340 2835);
FORCEPROP 1 LASTPIN (-350 2825) BN 6
J 2
(-338 2833);
DISPLAY 0.680851 (-338 2833);
PAINT GREEN (-338 2833);
FORCEPROP 2 LAST CDS_LIB standard
J 0
(-400 2825);
DISPLAY INVISIBLE (-400 2825);
FORCEPROP 1 LAST BODY_TYPE PLUMBING
J 2
(-400 2875);
DISPLAY 0.872340 (-400 2875);
PAINT GREEN (-400 2875);
DISPLAY INVISIBLE (-400 2875);
FORCEPROP 1 LAST HDL_TAP TRUE
J 2
(-725 2700);
DISPLAY 0.872340 (-725 2700);
DISPLAY INVISIBLE (-725 2700);
FORCEPROP 1 LAST PATH I103
J 2
(-398 2825);
DISPLAY 0.872340 (-398 2825);
PAINT GREEN (-398 2825);
DISPLAY INVISIBLE (-398 2825);
FORCEADD TAP..1
R 2
(-400 2875);
FORCEPROP 3 LASTPIN (-350 2875) SIG_NAME UPI_CPU1_CPU0_P1P0_DP<7>
J 0
(-340 2885);
DISPLAY 0.659574 (-340 2885);
PAINT MONO (-340 2885);
DISPLAY INVISIBLE (-340 2885);
FORCEPROP 1 LASTPIN (-350 2875) BN 7
J 2
(-338 2883);
DISPLAY 0.680851 (-338 2883);
PAINT GREEN (-338 2883);
FORCEPROP 2 LAST CDS_LIB standard
J 0
(-400 2875);
DISPLAY INVISIBLE (-400 2875);
FORCEPROP 1 LAST BODY_TYPE PLUMBING
J 2
(-400 2925);
DISPLAY 0.872340 (-400 2925);
PAINT GREEN (-400 2925);
DISPLAY INVISIBLE (-400 2925);
FORCEPROP 1 LAST HDL_TAP TRUE
J 2
(-725 2750);
DISPLAY 0.872340 (-725 2750);
DISPLAY INVISIBLE (-725 2750);
FORCEPROP 1 LAST PATH I104
J 2
(-398 2875);
DISPLAY 0.872340 (-398 2875);
PAINT GREEN (-398 2875);
DISPLAY INVISIBLE (-398 2875);
FORCEADD TAP..1
(2975 2375);
FORCEPROP 3 LASTPIN (2925 2375) SIG_NAME UPI_CPU0_CPU1_P0P1_DP<22>
J 0
(2935 2385);
DISPLAY 0.659574 (2935 2385);
PAINT MONO (2935 2385);
DISPLAY INVISIBLE (2935 2385);
FORCEPROP 1 LASTPIN (2925 2375) BN 22
J 0
(2913 2383);
DISPLAY 0.680851 (2913 2383);
PAINT GREEN (2913 2383);
FORCEPROP 2 LAST CDS_LIB standard
J 0
(2975 2375);
DISPLAY INVISIBLE (2975 2375);
FORCEPROP 1 LAST BODY_TYPE PLUMBING
J 0
(2975 2425);
DISPLAY 0.872340 (2975 2425);
PAINT GREEN (2975 2425);
DISPLAY INVISIBLE (2975 2425);
FORCEPROP 1 LAST HDL_TAP TRUE
J 0
(3300 2250);
DISPLAY 0.872340 (3300 2250);
DISPLAY INVISIBLE (3300 2250);
FORCEPROP 1 LAST PATH I106
J 0
(2973 2375);
DISPLAY 0.872340 (2973 2375);
PAINT GREEN (2973 2375);
DISPLAY INVISIBLE (2973 2375);
FORCEADD TAP..1
(3175 2425);
FORCEPROP 3 LASTPIN (3125 2425) SIG_NAME UPI_CPU0_CPU1_P0P1_DN<23>
J 0
(3135 2435);
DISPLAY 0.659574 (3135 2435);
PAINT MONO (3135 2435);
DISPLAY INVISIBLE (3135 2435);
FORCEPROP 1 LASTPIN (3125 2425) BN 23
J 0
(3113 2433);
DISPLAY 0.680851 (3113 2433);
PAINT GREEN (3113 2433);
FORCEPROP 2 LAST CDS_LIB standard
J 0
(3175 2425);
DISPLAY INVISIBLE (3175 2425);
FORCEPROP 1 LAST BODY_TYPE PLUMBING
J 0
(3175 2475);
DISPLAY 0.872340 (3175 2475);
PAINT GREEN (3175 2475);
DISPLAY INVISIBLE (3175 2475);
FORCEPROP 1 LAST HDL_TAP TRUE
J 0
(3500 2300);
DISPLAY 0.872340 (3500 2300);
DISPLAY INVISIBLE (3500 2300);
FORCEPROP 1 LAST PATH I107
J 0
(3173 2425);
DISPLAY 0.872340 (3173 2425);
PAINT GREEN (3173 2425);
DISPLAY INVISIBLE (3173 2425);
FORCEADD TAP..1
(2975 2325);
FORCEPROP 3 LASTPIN (2925 2325) SIG_NAME UPI_CPU0_CPU1_P0P1_DP<21>
J 0
(2935 2335);
DISPLAY 0.659574 (2935 2335);
PAINT MONO (2935 2335);
DISPLAY INVISIBLE (2935 2335);
FORCEPROP 1 LASTPIN (2925 2325) BN 21
J 0
(2913 2333);
DISPLAY 0.680851 (2913 2333);
PAINT GREEN (2913 2333);
FORCEPROP 2 LAST CDS_LIB standard
J 0
(2975 2325);
DISPLAY INVISIBLE (2975 2325);
FORCEPROP 1 LAST BODY_TYPE PLUMBING
J 0
(2975 2375);
DISPLAY 0.872340 (2975 2375);
PAINT GREEN (2975 2375);
DISPLAY INVISIBLE (2975 2375);
FORCEPROP 1 LAST HDL_TAP TRUE
J 0
(3300 2200);
DISPLAY 0.872340 (3300 2200);
DISPLAY INVISIBLE (3300 2200);
FORCEPROP 1 LAST PATH I108
J 0
(2973 2325);
DISPLAY 0.872340 (2973 2325);
PAINT GREEN (2973 2325);
DISPLAY INVISIBLE (2973 2325);
FORCEADD TAP..1
(2975 2275);
FORCEPROP 3 LASTPIN (2925 2275) SIG_NAME UPI_CPU0_CPU1_P0P1_DP<20>
J 0
(2935 2285);
DISPLAY 0.659574 (2935 2285);
PAINT MONO (2935 2285);
DISPLAY INVISIBLE (2935 2285);
FORCEPROP 1 LASTPIN (2925 2275) BN 20
J 0
(2913 2283);
DISPLAY 0.680851 (2913 2283);
PAINT GREEN (2913 2283);
FORCEPROP 2 LAST CDS_LIB standard
J 0
(2975 2275);
DISPLAY INVISIBLE (2975 2275);
FORCEPROP 1 LAST BODY_TYPE PLUMBING
J 0
(2975 2325);
DISPLAY 0.872340 (2975 2325);
PAINT GREEN (2975 2325);
DISPLAY INVISIBLE (2975 2325);
FORCEPROP 1 LAST HDL_TAP TRUE
J 0
(3300 2150);
DISPLAY 0.872340 (3300 2150);
DISPLAY INVISIBLE (3300 2150);
FORCEPROP 1 LAST PATH I109
J 0
(2973 2275);
DISPLAY 0.872340 (2973 2275);
PAINT GREEN (2973 2275);
DISPLAY INVISIBLE (2973 2275);
FORCEADD TAP..1
(3175 2225);
FORCEPROP 3 LASTPIN (3125 2225) SIG_NAME UPI_CPU0_CPU1_P0P1_DN<19>
J 0
(3135 2235);
DISPLAY 0.659574 (3135 2235);
PAINT MONO (3135 2235);
DISPLAY INVISIBLE (3135 2235);
FORCEPROP 1 LASTPIN (3125 2225) BN 19
J 0
(3113 2233);
DISPLAY 0.680851 (3113 2233);
PAINT GREEN (3113 2233);
FORCEPROP 2 LAST CDS_LIB standard
J 0
(3175 2225);
DISPLAY INVISIBLE (3175 2225);
FORCEPROP 1 LAST BODY_TYPE PLUMBING
J 0
(3175 2275);
DISPLAY 0.872340 (3175 2275);
PAINT GREEN (3175 2275);
DISPLAY INVISIBLE (3175 2275);
FORCEPROP 1 LAST HDL_TAP TRUE
J 0
(3500 2100);
DISPLAY 0.872340 (3500 2100);
DISPLAY INVISIBLE (3500 2100);
FORCEPROP 1 LAST PATH I110
J 0
(3173 2225);
DISPLAY 0.872340 (3173 2225);
PAINT GREEN (3173 2225);
DISPLAY INVISIBLE (3173 2225);
FORCEADD TAP..1
(3175 2175);
FORCEPROP 3 LASTPIN (3125 2175) SIG_NAME UPI_CPU0_CPU1_P0P1_DN<18>
J 0
(3135 2185);
DISPLAY 0.659574 (3135 2185);
PAINT MONO (3135 2185);
DISPLAY INVISIBLE (3135 2185);
FORCEPROP 1 LASTPIN (3125 2175) BN 18
J 0
(3113 2183);
DISPLAY 0.680851 (3113 2183);
PAINT GREEN (3113 2183);
FORCEPROP 2 LAST CDS_LIB standard
J 0
(3175 2175);
DISPLAY INVISIBLE (3175 2175);
FORCEPROP 1 LAST BODY_TYPE PLUMBING
J 0
(3175 2225);
DISPLAY 0.872340 (3175 2225);
PAINT GREEN (3175 2225);
DISPLAY INVISIBLE (3175 2225);
FORCEPROP 1 LAST HDL_TAP TRUE
J 0
(3500 2050);
DISPLAY 0.872340 (3500 2050);
DISPLAY INVISIBLE (3500 2050);
FORCEPROP 1 LAST PATH I111
J 0
(3173 2175);
DISPLAY 0.872340 (3173 2175);
PAINT GREEN (3173 2175);
DISPLAY INVISIBLE (3173 2175);
FORCEADD TAP..1
(3175 2125);
FORCEPROP 3 LASTPIN (3125 2125) SIG_NAME UPI_CPU0_CPU1_P0P1_DN<17>
J 0
(3135 2135);
DISPLAY 0.659574 (3135 2135);
PAINT MONO (3135 2135);
DISPLAY INVISIBLE (3135 2135);
FORCEPROP 1 LASTPIN (3125 2125) BN 17
J 0
(3113 2133);
DISPLAY 0.680851 (3113 2133);
PAINT GREEN (3113 2133);
FORCEPROP 2 LAST CDS_LIB standard
J 0
(3175 2125);
DISPLAY INVISIBLE (3175 2125);
FORCEPROP 1 LAST BODY_TYPE PLUMBING
J 0
(3175 2175);
DISPLAY 0.872340 (3175 2175);
PAINT GREEN (3175 2175);
DISPLAY INVISIBLE (3175 2175);
FORCEPROP 1 LAST HDL_TAP TRUE
J 0
(3500 2000);
DISPLAY 0.872340 (3500 2000);
DISPLAY INVISIBLE (3500 2000);
FORCEPROP 1 LAST PATH I112
J 0
(3173 2125);
DISPLAY 0.872340 (3173 2125);
PAINT GREEN (3173 2125);
DISPLAY INVISIBLE (3173 2125);
FORCEADD TAP..1
(3175 2075);
FORCEPROP 3 LASTPIN (3125 2075) SIG_NAME UPI_CPU0_CPU1_P0P1_DN<16>
J 0
(3135 2085);
DISPLAY 0.659574 (3135 2085);
PAINT MONO (3135 2085);
DISPLAY INVISIBLE (3135 2085);
FORCEPROP 1 LASTPIN (3125 2075) BN 16
J 0
(3113 2083);
DISPLAY 0.680851 (3113 2083);
PAINT GREEN (3113 2083);
FORCEPROP 2 LAST CDS_LIB standard
J 0
(3175 2075);
PAINT MONO (3175 2075);
DISPLAY INVISIBLE (3175 2075);
FORCEPROP 1 LAST BODY_TYPE PLUMBING
J 0
(3175 2125);
DISPLAY 0.872340 (3175 2125);
PAINT GREEN (3175 2125);
DISPLAY INVISIBLE (3175 2125);
FORCEPROP 1 LAST HDL_TAP TRUE
J 0
(3500 1950);
DISPLAY 0.872340 (3500 1950);
DISPLAY INVISIBLE (3500 1950);
FORCEPROP 1 LAST PATH I113
J 0
(3173 2075);
DISPLAY 0.872340 (3173 2075);
PAINT GREEN (3173 2075);
DISPLAY INVISIBLE (3173 2075);
FORCEADD TAP..1
(3175 1975);
FORCEPROP 3 LASTPIN (3125 1975) SIG_NAME UPI_CPU0_CPU1_P0P1_DN<14>
J 0
(3135 1985);
DISPLAY 0.659574 (3135 1985);
PAINT MONO (3135 1985);
DISPLAY INVISIBLE (3135 1985);
FORCEPROP 1 LASTPIN (3125 1975) BN 14
J 0
(3113 1983);
DISPLAY 0.680851 (3113 1983);
PAINT GREEN (3113 1983);
FORCEPROP 2 LAST CDS_LIB standard
J 0
(3175 1975);
PAINT MONO (3175 1975);
DISPLAY INVISIBLE (3175 1975);
FORCEPROP 1 LAST BODY_TYPE PLUMBING
J 0
(3175 2025);
DISPLAY 0.872340 (3175 2025);
PAINT GREEN (3175 2025);
DISPLAY INVISIBLE (3175 2025);
FORCEPROP 1 LAST HDL_TAP TRUE
J 0
(3500 1850);
DISPLAY 0.872340 (3500 1850);
DISPLAY INVISIBLE (3500 1850);
FORCEPROP 1 LAST PATH I114
J 0
(3173 1975);
DISPLAY 0.872340 (3173 1975);
PAINT GREEN (3173 1975);
DISPLAY INVISIBLE (3173 1975);
FORCEADD TAP..1
(2975 1925);
FORCEPROP 3 LASTPIN (2925 1925) SIG_NAME UPI_CPU0_CPU1_P0P1_DP<13>
J 0
(2935 1935);
DISPLAY 0.659574 (2935 1935);
PAINT MONO (2935 1935);
DISPLAY INVISIBLE (2935 1935);
FORCEPROP 1 LASTPIN (2925 1925) BN 13
J 0
(2913 1933);
DISPLAY 0.680851 (2913 1933);
PAINT GREEN (2913 1933);
FORCEPROP 2 LAST CDS_LIB standard
J 0
(2975 1925);
PAINT MONO (2975 1925);
DISPLAY INVISIBLE (2975 1925);
FORCEPROP 1 LAST BODY_TYPE PLUMBING
J 0
(2975 1975);
DISPLAY 0.872340 (2975 1975);
PAINT GREEN (2975 1975);
DISPLAY INVISIBLE (2975 1975);
FORCEPROP 1 LAST HDL_TAP TRUE
J 0
(3300 1800);
DISPLAY 0.872340 (3300 1800);
DISPLAY INVISIBLE (3300 1800);
FORCEPROP 1 LAST PATH I115
J 0
(2973 1925);
DISPLAY 0.872340 (2973 1925);
PAINT GREEN (2973 1925);
DISPLAY INVISIBLE (2973 1925);
FORCEADD TAP..1
(2975 2025);
FORCEPROP 3 LASTPIN (2925 2025) SIG_NAME UPI_CPU0_CPU1_P0P1_DP<15>
J 0
(2935 2035);
DISPLAY 0.659574 (2935 2035);
PAINT MONO (2935 2035);
DISPLAY INVISIBLE (2935 2035);
FORCEPROP 1 LASTPIN (2925 2025) BN 15
J 0
(2913 2033);
DISPLAY 0.680851 (2913 2033);
PAINT GREEN (2913 2033);
FORCEPROP 2 LAST CDS_LIB standard
J 0
(2975 2025);
PAINT MONO (2975 2025);
DISPLAY INVISIBLE (2975 2025);
FORCEPROP 1 LAST BODY_TYPE PLUMBING
J 0
(2975 2075);
DISPLAY 0.872340 (2975 2075);
PAINT GREEN (2975 2075);
DISPLAY INVISIBLE (2975 2075);
FORCEPROP 1 LAST HDL_TAP TRUE
J 0
(3300 1900);
DISPLAY 0.872340 (3300 1900);
DISPLAY INVISIBLE (3300 1900);
FORCEPROP 1 LAST PATH I116
J 0
(2973 2025);
DISPLAY 0.872340 (2973 2025);
PAINT GREEN (2973 2025);
DISPLAY INVISIBLE (2973 2025);
FORCEADD TAP..1
(2975 1875);
FORCEPROP 3 LASTPIN (2925 1875) SIG_NAME UPI_CPU0_CPU1_P0P1_DP<12>
J 0
(2935 1885);
DISPLAY 0.659574 (2935 1885);
PAINT MONO (2935 1885);
DISPLAY INVISIBLE (2935 1885);
FORCEPROP 1 LASTPIN (2925 1875) BN 12
J 0
(2913 1883);
DISPLAY 0.680851 (2913 1883);
PAINT GREEN (2913 1883);
FORCEPROP 2 LAST CDS_LIB standard
J 0
(2975 1875);
PAINT MONO (2975 1875);
DISPLAY INVISIBLE (2975 1875);
FORCEPROP 1 LAST BODY_TYPE PLUMBING
J 0
(2975 1925);
DISPLAY 0.872340 (2975 1925);
PAINT GREEN (2975 1925);
DISPLAY INVISIBLE (2975 1925);
FORCEPROP 1 LAST HDL_TAP TRUE
J 0
(3300 1750);
DISPLAY 0.872340 (3300 1750);
DISPLAY INVISIBLE (3300 1750);
FORCEPROP 1 LAST PATH I117
J 0
(2973 1875);
DISPLAY 0.872340 (2973 1875);
PAINT GREEN (2973 1875);
DISPLAY INVISIBLE (2973 1875);
FORCEADD TAP..1
(3175 1825);
FORCEPROP 3 LASTPIN (3125 1825) SIG_NAME UPI_CPU0_CPU1_P0P1_DN<11>
J 0
(3135 1835);
DISPLAY 0.659574 (3135 1835);
PAINT MONO (3135 1835);
DISPLAY INVISIBLE (3135 1835);
FORCEPROP 1 LASTPIN (3125 1825) BN 11
J 0
(3113 1833);
DISPLAY 0.680851 (3113 1833);
PAINT GREEN (3113 1833);
FORCEPROP 2 LAST CDS_LIB standard
J 0
(3175 1825);
PAINT MONO (3175 1825);
DISPLAY INVISIBLE (3175 1825);
FORCEPROP 1 LAST BODY_TYPE PLUMBING
J 0
(3175 1875);
DISPLAY 0.872340 (3175 1875);
PAINT GREEN (3175 1875);
DISPLAY INVISIBLE (3175 1875);
FORCEPROP 1 LAST HDL_TAP TRUE
J 0
(3500 1700);
DISPLAY 0.872340 (3500 1700);
DISPLAY INVISIBLE (3500 1700);
FORCEPROP 1 LAST PATH I118
J 0
(3173 1825);
DISPLAY 0.872340 (3173 1825);
PAINT GREEN (3173 1825);
DISPLAY INVISIBLE (3173 1825);
FORCEADD TAP..1
(3175 1725);
FORCEPROP 3 LASTPIN (3125 1725) SIG_NAME UPI_CPU0_CPU1_P0P1_DN<9>
J 0
(3135 1735);
DISPLAY 0.659574 (3135 1735);
PAINT MONO (3135 1735);
DISPLAY INVISIBLE (3135 1735);
FORCEPROP 1 LASTPIN (3125 1725) BN 9
J 0
(3113 1733);
DISPLAY 0.680851 (3113 1733);
PAINT GREEN (3113 1733);
FORCEPROP 2 LAST CDS_LIB standard
J 0
(3175 1725);
PAINT MONO (3175 1725);
DISPLAY INVISIBLE (3175 1725);
FORCEPROP 1 LAST BODY_TYPE PLUMBING
J 0
(3175 1775);
DISPLAY 0.872340 (3175 1775);
PAINT GREEN (3175 1775);
DISPLAY INVISIBLE (3175 1775);
FORCEPROP 1 LAST HDL_TAP TRUE
J 0
(3500 1600);
DISPLAY 0.872340 (3500 1600);
DISPLAY INVISIBLE (3500 1600);
FORCEPROP 1 LAST PATH I119
J 0
(3173 1725);
DISPLAY 0.872340 (3173 1725);
PAINT GREEN (3173 1725);
DISPLAY INVISIBLE (3173 1725);
FORCEADD TAP..1
(3175 1675);
FORCEPROP 3 LASTPIN (3125 1675) SIG_NAME UPI_CPU0_CPU1_P0P1_DN<8>
J 0
(3135 1685);
DISPLAY 0.659574 (3135 1685);
PAINT MONO (3135 1685);
DISPLAY INVISIBLE (3135 1685);
FORCEPROP 1 LASTPIN (3125 1675) BN 8
J 0
(3113 1683);
DISPLAY 0.680851 (3113 1683);
PAINT GREEN (3113 1683);
FORCEPROP 2 LAST CDS_LIB standard
J 0
(3175 1675);
PAINT MONO (3175 1675);
DISPLAY INVISIBLE (3175 1675);
FORCEPROP 1 LAST BODY_TYPE PLUMBING
J 0
(3175 1725);
DISPLAY 0.872340 (3175 1725);
PAINT GREEN (3175 1725);
DISPLAY INVISIBLE (3175 1725);
FORCEPROP 1 LAST HDL_TAP TRUE
J 0
(3500 1550);
DISPLAY 0.872340 (3500 1550);
DISPLAY INVISIBLE (3500 1550);
FORCEPROP 1 LAST PATH I120
J 0
(3173 1675);
DISPLAY 0.872340 (3173 1675);
PAINT GREEN (3173 1675);
DISPLAY INVISIBLE (3173 1675);
FORCEADD TAP..1
(3175 1775);
FORCEPROP 3 LASTPIN (3125 1775) SIG_NAME UPI_CPU0_CPU1_P0P1_DN<10>
J 0
(3135 1785);
DISPLAY 0.659574 (3135 1785);
PAINT MONO (3135 1785);
DISPLAY INVISIBLE (3135 1785);
FORCEPROP 1 LASTPIN (3125 1775) BN 10
J 0
(3113 1783);
DISPLAY 0.680851 (3113 1783);
PAINT GREEN (3113 1783);
FORCEPROP 2 LAST CDS_LIB standard
J 0
(3175 1775);
PAINT MONO (3175 1775);
DISPLAY INVISIBLE (3175 1775);
FORCEPROP 1 LAST BODY_TYPE PLUMBING
J 0
(3175 1825);
DISPLAY 0.872340 (3175 1825);
PAINT GREEN (3175 1825);
DISPLAY INVISIBLE (3175 1825);
FORCEPROP 1 LAST HDL_TAP TRUE
J 0
(3500 1650);
DISPLAY 0.872340 (3500 1650);
DISPLAY INVISIBLE (3500 1650);
FORCEPROP 1 LAST PATH I121
J 0
(3173 1775);
DISPLAY 0.872340 (3173 1775);
PAINT GREEN (3173 1775);
DISPLAY INVISIBLE (3173 1775);
FORCEADD TAP..1
(3175 1425);
FORCEPROP 3 LASTPIN (3125 1425) SIG_NAME UPI_CPU0_CPU1_P0P1_DN<3>
J 0
(3135 1435);
DISPLAY 0.659574 (3135 1435);
PAINT MONO (3135 1435);
DISPLAY INVISIBLE (3135 1435);
FORCEPROP 1 LASTPIN (3125 1425) BN 3
J 0
(3113 1433);
DISPLAY 0.680851 (3113 1433);
PAINT GREEN (3113 1433);
FORCEPROP 2 LAST CDS_LIB standard
J 0
(3175 1425);
PAINT MONO (3175 1425);
DISPLAY INVISIBLE (3175 1425);
FORCEPROP 1 LAST BODY_TYPE PLUMBING
J 0
(3175 1475);
DISPLAY 0.872340 (3175 1475);
PAINT GREEN (3175 1475);
DISPLAY INVISIBLE (3175 1475);
FORCEPROP 1 LAST HDL_TAP TRUE
J 0
(3500 1300);
DISPLAY 0.872340 (3500 1300);
DISPLAY INVISIBLE (3500 1300);
FORCEPROP 1 LAST PATH I122
J 0
(3173 1425);
DISPLAY 0.872340 (3173 1425);
PAINT GREEN (3173 1425);
DISPLAY INVISIBLE (3173 1425);
FORCEADD TAP..1
(3175 1475);
FORCEPROP 3 LASTPIN (3125 1475) SIG_NAME UPI_CPU0_CPU1_P0P1_DN<4>
J 0
(3135 1485);
DISPLAY 0.659574 (3135 1485);
PAINT MONO (3135 1485);
DISPLAY INVISIBLE (3135 1485);
FORCEPROP 1 LASTPIN (3125 1475) BN 4
J 0
(3113 1483);
DISPLAY 0.680851 (3113 1483);
PAINT GREEN (3113 1483);
FORCEPROP 2 LAST CDS_LIB standard
J 0
(3175 1475);
PAINT MONO (3175 1475);
DISPLAY INVISIBLE (3175 1475);
FORCEPROP 1 LAST BODY_TYPE PLUMBING
J 0
(3175 1525);
DISPLAY 0.872340 (3175 1525);
PAINT GREEN (3175 1525);
DISPLAY INVISIBLE (3175 1525);
FORCEPROP 1 LAST HDL_TAP TRUE
J 0
(3500 1350);
DISPLAY 0.872340 (3500 1350);
DISPLAY INVISIBLE (3500 1350);
FORCEPROP 1 LAST PATH I123
J 0
(3173 1475);
DISPLAY 0.872340 (3173 1475);
PAINT GREEN (3173 1475);
DISPLAY INVISIBLE (3173 1475);
FORCEADD TAP..1
(3175 1525);
FORCEPROP 3 LASTPIN (3125 1525) SIG_NAME UPI_CPU0_CPU1_P0P1_DN<5>
J 0
(3135 1535);
DISPLAY 0.659574 (3135 1535);
PAINT MONO (3135 1535);
DISPLAY INVISIBLE (3135 1535);
FORCEPROP 1 LASTPIN (3125 1525) BN 5
J 0
(3113 1533);
DISPLAY 0.680851 (3113 1533);
PAINT GREEN (3113 1533);
FORCEPROP 2 LAST CDS_LIB standard
J 0
(3175 1525);
PAINT MONO (3175 1525);
DISPLAY INVISIBLE (3175 1525);
FORCEPROP 1 LAST BODY_TYPE PLUMBING
J 0
(3175 1575);
DISPLAY 0.872340 (3175 1575);
PAINT GREEN (3175 1575);
DISPLAY INVISIBLE (3175 1575);
FORCEPROP 1 LAST HDL_TAP TRUE
J 0
(3500 1400);
DISPLAY 0.872340 (3500 1400);
DISPLAY INVISIBLE (3500 1400);
FORCEPROP 1 LAST PATH I124
J 0
(3173 1525);
DISPLAY 0.872340 (3173 1525);
PAINT GREEN (3173 1525);
DISPLAY INVISIBLE (3173 1525);
FORCEADD TAP..1
(3175 1575);
FORCEPROP 3 LASTPIN (3125 1575) SIG_NAME UPI_CPU0_CPU1_P0P1_DN<6>
J 0
(3135 1585);
DISPLAY 0.659574 (3135 1585);
PAINT MONO (3135 1585);
DISPLAY INVISIBLE (3135 1585);
FORCEPROP 1 LASTPIN (3125 1575) BN 6
J 0
(3113 1583);
DISPLAY 0.680851 (3113 1583);
PAINT GREEN (3113 1583);
FORCEPROP 2 LAST CDS_LIB standard
J 0
(3175 1575);
PAINT MONO (3175 1575);
DISPLAY INVISIBLE (3175 1575);
FORCEPROP 1 LAST BODY_TYPE PLUMBING
J 0
(3175 1625);
DISPLAY 0.872340 (3175 1625);
PAINT GREEN (3175 1625);
DISPLAY INVISIBLE (3175 1625);
FORCEPROP 1 LAST HDL_TAP TRUE
J 0
(3500 1450);
DISPLAY 0.872340 (3500 1450);
DISPLAY INVISIBLE (3500 1450);
FORCEPROP 1 LAST PATH I125
J 0
(3173 1575);
DISPLAY 0.872340 (3173 1575);
PAINT GREEN (3173 1575);
DISPLAY INVISIBLE (3173 1575);
FORCEADD TAP..1
(3175 1625);
FORCEPROP 3 LASTPIN (3125 1625) SIG_NAME UPI_CPU0_CPU1_P0P1_DN<7>
J 0
(3135 1635);
DISPLAY 0.659574 (3135 1635);
PAINT MONO (3135 1635);
DISPLAY INVISIBLE (3135 1635);
FORCEPROP 1 LASTPIN (3125 1625) BN 7
J 0
(3113 1633);
DISPLAY 0.680851 (3113 1633);
PAINT GREEN (3113 1633);
FORCEPROP 2 LAST CDS_LIB standard
J 0
(3175 1625);
PAINT MONO (3175 1625);
DISPLAY INVISIBLE (3175 1625);
FORCEPROP 1 LAST BODY_TYPE PLUMBING
J 0
(3175 1675);
DISPLAY 0.872340 (3175 1675);
PAINT GREEN (3175 1675);
DISPLAY INVISIBLE (3175 1675);
FORCEPROP 1 LAST HDL_TAP TRUE
J 0
(3500 1500);
DISPLAY 0.872340 (3500 1500);
DISPLAY INVISIBLE (3500 1500);
FORCEPROP 1 LAST PATH I126
J 0
(3173 1625);
DISPLAY 0.872340 (3173 1625);
PAINT GREEN (3173 1625);
DISPLAY INVISIBLE (3173 1625);
FORCEADD TAP..1
(3175 1325);
FORCEPROP 3 LASTPIN (3125 1325) SIG_NAME UPI_CPU0_CPU1_P0P1_DN<1>
J 0
(3135 1335);
DISPLAY 0.659574 (3135 1335);
PAINT MONO (3135 1335);
DISPLAY INVISIBLE (3135 1335);
FORCEPROP 1 LASTPIN (3125 1325) BN 1
J 0
(3113 1333);
DISPLAY 0.680851 (3113 1333);
PAINT GREEN (3113 1333);
FORCEPROP 2 LAST CDS_LIB standard
J 0
(3175 1325);
PAINT MONO (3175 1325);
DISPLAY INVISIBLE (3175 1325);
FORCEPROP 1 LAST BODY_TYPE PLUMBING
J 0
(3175 1375);
DISPLAY 0.872340 (3175 1375);
PAINT GREEN (3175 1375);
DISPLAY INVISIBLE (3175 1375);
FORCEPROP 1 LAST HDL_TAP TRUE
J 0
(3500 1200);
DISPLAY 0.872340 (3500 1200);
DISPLAY INVISIBLE (3500 1200);
FORCEPROP 1 LAST PATH I127
J 0
(3173 1325);
DISPLAY 0.872340 (3173 1325);
PAINT GREEN (3173 1325);
DISPLAY INVISIBLE (3173 1325);
FORCEADD TAP..1
(3175 1275);
FORCEPROP 3 LASTPIN (3125 1275) SIG_NAME UPI_CPU0_CPU1_P0P1_DN<0>
J 0
(3135 1285);
DISPLAY 0.659574 (3135 1285);
PAINT MONO (3135 1285);
DISPLAY INVISIBLE (3135 1285);
FORCEPROP 1 LASTPIN (3125 1275) BN 0
J 0
(3113 1283);
DISPLAY 0.680851 (3113 1283);
PAINT GREEN (3113 1283);
FORCEPROP 2 LAST CDS_LIB standard
J 0
(3175 1275);
PAINT MONO (3175 1275);
DISPLAY INVISIBLE (3175 1275);
FORCEPROP 1 LAST BODY_TYPE PLUMBING
J 0
(3175 1325);
DISPLAY 0.872340 (3175 1325);
PAINT GREEN (3175 1325);
DISPLAY INVISIBLE (3175 1325);
FORCEPROP 1 LAST HDL_TAP TRUE
J 0
(3500 1150);
DISPLAY 0.872340 (3500 1150);
DISPLAY INVISIBLE (3500 1150);
FORCEPROP 1 LAST PATH I128
J 0
(3173 1275);
DISPLAY 0.872340 (3173 1275);
PAINT GREEN (3173 1275);
DISPLAY INVISIBLE (3173 1275);
FORCEADD TAP..1
(3175 1375);
FORCEPROP 3 LASTPIN (3125 1375) SIG_NAME UPI_CPU0_CPU1_P0P1_DN<2>
J 0
(3135 1385);
DISPLAY 0.659574 (3135 1385);
PAINT MONO (3135 1385);
DISPLAY INVISIBLE (3135 1385);
FORCEPROP 1 LASTPIN (3125 1375) BN 2
J 0
(3113 1383);
DISPLAY 0.680851 (3113 1383);
PAINT GREEN (3113 1383);
FORCEPROP 2 LAST CDS_LIB standard
J 0
(3175 1375);
PAINT MONO (3175 1375);
DISPLAY INVISIBLE (3175 1375);
FORCEPROP 1 LAST BODY_TYPE PLUMBING
J 0
(3175 1425);
DISPLAY 0.872340 (3175 1425);
PAINT GREEN (3175 1425);
DISPLAY INVISIBLE (3175 1425);
FORCEPROP 1 LAST HDL_TAP TRUE
J 0
(3500 1250);
DISPLAY 0.872340 (3500 1250);
DISPLAY INVISIBLE (3500 1250);
FORCEPROP 1 LAST PATH I129
J 0
(3173 1375);
DISPLAY 0.872340 (3173 1375);
PAINT GREEN (3173 1375);
DISPLAY INVISIBLE (3173 1375);
FORCEADD TAP..1
(2975 2725);
FORCEPROP 3 LASTPIN (2925 2725) SIG_NAME UPI_CPU0_CPU1_P0P1_DP<4>
J 0
(2935 2735);
DISPLAY 0.659574 (2935 2735);
PAINT MONO (2935 2735);
DISPLAY INVISIBLE (2935 2735);
FORCEPROP 1 LASTPIN (2925 2725) BN 4
J 0
(2913 2733);
DISPLAY 0.680851 (2913 2733);
PAINT GREEN (2913 2733);
FORCEPROP 2 LAST CDS_LIB standard
J 0
(2975 2725);
PAINT MONO (2975 2725);
DISPLAY INVISIBLE (2975 2725);
FORCEPROP 1 LAST BODY_TYPE PLUMBING
J 0
(2975 2775);
DISPLAY 0.872340 (2975 2775);
PAINT GREEN (2975 2775);
DISPLAY INVISIBLE (2975 2775);
FORCEPROP 1 LAST HDL_TAP TRUE
J 0
(3300 2600);
DISPLAY 0.872340 (3300 2600);
DISPLAY INVISIBLE (3300 2600);
FORCEPROP 1 LAST PATH I130
J 0
(2973 2725);
DISPLAY 0.872340 (2973 2725);
PAINT GREEN (2973 2725);
DISPLAY INVISIBLE (2973 2725);
FORCEADD TAP..1
(2975 2675);
FORCEPROP 3 LASTPIN (2925 2675) SIG_NAME UPI_CPU0_CPU1_P0P1_DP<3>
J 0
(2935 2685);
DISPLAY 0.659574 (2935 2685);
PAINT MONO (2935 2685);
DISPLAY INVISIBLE (2935 2685);
FORCEPROP 1 LASTPIN (2925 2675) BN 3
J 0
(2913 2683);
DISPLAY 0.680851 (2913 2683);
PAINT GREEN (2913 2683);
FORCEPROP 2 LAST CDS_LIB standard
J 0
(2975 2675);
PAINT MONO (2975 2675);
DISPLAY INVISIBLE (2975 2675);
FORCEPROP 1 LAST BODY_TYPE PLUMBING
J 0
(2975 2725);
DISPLAY 0.872340 (2975 2725);
PAINT GREEN (2975 2725);
DISPLAY INVISIBLE (2975 2725);
FORCEPROP 1 LAST HDL_TAP TRUE
J 0
(3300 2550);
DISPLAY 0.872340 (3300 2550);
DISPLAY INVISIBLE (3300 2550);
FORCEPROP 1 LAST PATH I131
J 0
(2973 2675);
DISPLAY 0.872340 (2973 2675);
PAINT GREEN (2973 2675);
DISPLAY INVISIBLE (2973 2675);
FORCEADD TAP..1
(2975 2775);
FORCEPROP 3 LASTPIN (2925 2775) SIG_NAME UPI_CPU0_CPU1_P0P1_DP<5>
J 0
(2935 2785);
DISPLAY 0.659574 (2935 2785);
PAINT MONO (2935 2785);
DISPLAY INVISIBLE (2935 2785);
FORCEPROP 1 LASTPIN (2925 2775) BN 5
J 0
(2913 2783);
DISPLAY 0.680851 (2913 2783);
PAINT GREEN (2913 2783);
FORCEPROP 2 LAST CDS_LIB standard
J 0
(2975 2775);
PAINT MONO (2975 2775);
DISPLAY INVISIBLE (2975 2775);
FORCEPROP 1 LAST BODY_TYPE PLUMBING
J 0
(2975 2825);
DISPLAY 0.872340 (2975 2825);
PAINT GREEN (2975 2825);
DISPLAY INVISIBLE (2975 2825);
FORCEPROP 1 LAST HDL_TAP TRUE
J 0
(3300 2650);
DISPLAY 0.872340 (3300 2650);
DISPLAY INVISIBLE (3300 2650);
FORCEPROP 1 LAST PATH I132
J 0
(2973 2775);
DISPLAY 0.872340 (2973 2775);
PAINT GREEN (2973 2775);
DISPLAY INVISIBLE (2973 2775);
FORCEADD TAP..1
(2975 2825);
FORCEPROP 3 LASTPIN (2925 2825) SIG_NAME UPI_CPU0_CPU1_P0P1_DP<6>
J 0
(2935 2835);
DISPLAY 0.659574 (2935 2835);
PAINT MONO (2935 2835);
DISPLAY INVISIBLE (2935 2835);
FORCEPROP 1 LASTPIN (2925 2825) BN 6
J 0
(2913 2833);
DISPLAY 0.680851 (2913 2833);
PAINT GREEN (2913 2833);
FORCEPROP 2 LAST CDS_LIB standard
J 0
(2975 2825);
PAINT MONO (2975 2825);
DISPLAY INVISIBLE (2975 2825);
FORCEPROP 1 LAST BODY_TYPE PLUMBING
J 0
(2975 2875);
DISPLAY 0.872340 (2975 2875);
PAINT GREEN (2975 2875);
DISPLAY INVISIBLE (2975 2875);
FORCEPROP 1 LAST HDL_TAP TRUE
J 0
(3300 2700);
DISPLAY 0.872340 (3300 2700);
DISPLAY INVISIBLE (3300 2700);
FORCEPROP 1 LAST PATH I133
J 0
(2973 2825);
DISPLAY 0.872340 (2973 2825);
PAINT GREEN (2973 2825);
DISPLAY INVISIBLE (2973 2825);
FORCEADD TAP..1
(2975 2875);
FORCEPROP 3 LASTPIN (2925 2875) SIG_NAME UPI_CPU0_CPU1_P0P1_DP<7>
J 0
(2935 2885);
DISPLAY 0.659574 (2935 2885);
PAINT MONO (2935 2885);
DISPLAY INVISIBLE (2935 2885);
FORCEPROP 1 LASTPIN (2925 2875) BN 7
J 0
(2913 2883);
DISPLAY 0.680851 (2913 2883);
PAINT GREEN (2913 2883);
FORCEPROP 2 LAST CDS_LIB standard
J 0
(2975 2875);
PAINT MONO (2975 2875);
DISPLAY INVISIBLE (2975 2875);
FORCEPROP 1 LAST BODY_TYPE PLUMBING
J 0
(2975 2925);
DISPLAY 0.872340 (2975 2925);
PAINT GREEN (2975 2925);
DISPLAY INVISIBLE (2975 2925);
FORCEPROP 1 LAST HDL_TAP TRUE
J 0
(3300 2750);
DISPLAY 0.872340 (3300 2750);
DISPLAY INVISIBLE (3300 2750);
FORCEPROP 1 LAST PATH I134
J 0
(2973 2875);
DISPLAY 0.872340 (2973 2875);
PAINT GREEN (2973 2875);
DISPLAY INVISIBLE (2973 2875);
FORCEADD TAP..1
(2975 2625);
FORCEPROP 3 LASTPIN (2925 2625) SIG_NAME UPI_CPU0_CPU1_P0P1_DP<2>
J 0
(2935 2635);
DISPLAY 0.659574 (2935 2635);
PAINT MONO (2935 2635);
DISPLAY INVISIBLE (2935 2635);
FORCEPROP 1 LASTPIN (2925 2625) BN 2
J 0
(2913 2633);
DISPLAY 0.680851 (2913 2633);
PAINT GREEN (2913 2633);
FORCEPROP 2 LAST CDS_LIB standard
J 0
(2975 2625);
PAINT MONO (2975 2625);
DISPLAY INVISIBLE (2975 2625);
FORCEPROP 1 LAST BODY_TYPE PLUMBING
J 0
(2975 2675);
DISPLAY 0.872340 (2975 2675);
PAINT GREEN (2975 2675);
DISPLAY INVISIBLE (2975 2675);
FORCEPROP 1 LAST HDL_TAP TRUE
J 0
(3300 2500);
DISPLAY 0.872340 (3300 2500);
DISPLAY INVISIBLE (3300 2500);
FORCEPROP 1 LAST PATH I135
J 0
(2973 2625);
DISPLAY 0.872340 (2973 2625);
PAINT GREEN (2973 2625);
DISPLAY INVISIBLE (2973 2625);
FORCEADD TAP..1
(2975 2525);
FORCEPROP 3 LASTPIN (2925 2525) SIG_NAME UPI_CPU0_CPU1_P0P1_DP<0>
J 0
(2935 2535);
DISPLAY 0.659574 (2935 2535);
PAINT MONO (2935 2535);
DISPLAY INVISIBLE (2935 2535);
FORCEPROP 1 LASTPIN (2925 2525) BN 0
J 0
(2913 2533);
DISPLAY 0.680851 (2913 2533);
PAINT GREEN (2913 2533);
FORCEPROP 2 LAST CDS_LIB standard
J 0
(2975 2525);
PAINT MONO (2975 2525);
DISPLAY INVISIBLE (2975 2525);
FORCEPROP 1 LAST BODY_TYPE PLUMBING
J 0
(2975 2575);
DISPLAY 0.872340 (2975 2575);
PAINT GREEN (2975 2575);
DISPLAY INVISIBLE (2975 2575);
FORCEPROP 1 LAST HDL_TAP TRUE
J 0
(3300 2400);
DISPLAY 0.872340 (3300 2400);
DISPLAY INVISIBLE (3300 2400);
FORCEPROP 1 LAST PATH I136
J 0
(2973 2525);
DISPLAY 0.872340 (2973 2525);
PAINT GREEN (2973 2525);
DISPLAY INVISIBLE (2973 2525);
FORCEADD TAP..1
(2975 2575);
FORCEPROP 3 LASTPIN (2925 2575) SIG_NAME UPI_CPU0_CPU1_P0P1_DP<1>
J 0
(2935 2585);
DISPLAY 0.659574 (2935 2585);
PAINT MONO (2935 2585);
DISPLAY INVISIBLE (2935 2585);
FORCEPROP 1 LASTPIN (2925 2575) BN 1
J 0
(2913 2583);
DISPLAY 0.680851 (2913 2583);
PAINT GREEN (2913 2583);
FORCEPROP 2 LAST CDS_LIB standard
J 0
(2975 2575);
PAINT MONO (2975 2575);
DISPLAY INVISIBLE (2975 2575);
FORCEPROP 1 LAST BODY_TYPE PLUMBING
J 0
(2975 2625);
DISPLAY 0.872340 (2975 2625);
PAINT GREEN (2975 2625);
DISPLAY INVISIBLE (2975 2625);
FORCEPROP 1 LAST HDL_TAP TRUE
J 0
(3300 2450);
DISPLAY 0.872340 (3300 2450);
DISPLAY INVISIBLE (3300 2450);
FORCEPROP 1 LAST PATH I137
J 0
(2973 2575);
DISPLAY 0.872340 (2973 2575);
PAINT GREEN (2973 2575);
DISPLAY INVISIBLE (2973 2575);
FORCEADD TAP..1
(3175 3575);
FORCEPROP 3 LASTPIN (3125 3575) SIG_NAME UPI_CPU0_CPU1_P0P1_DN<21>
J 0
(3135 3585);
DISPLAY 0.659574 (3135 3585);
PAINT MONO (3135 3585);
DISPLAY INVISIBLE (3135 3585);
FORCEPROP 1 LASTPIN (3125 3575) BN 21
J 0
(3113 3583);
DISPLAY 0.680851 (3113 3583);
PAINT GREEN (3113 3583);
FORCEPROP 2 LAST CDS_LIB standard
J 0
(3175 3575);
DISPLAY INVISIBLE (3175 3575);
FORCEPROP 1 LAST BODY_TYPE PLUMBING
J 0
(3175 3625);
DISPLAY 0.872340 (3175 3625);
PAINT GREEN (3175 3625);
DISPLAY INVISIBLE (3175 3625);
FORCEPROP 1 LAST HDL_TAP TRUE
J 0
(3500 3450);
DISPLAY 0.872340 (3500 3450);
DISPLAY INVISIBLE (3500 3450);
FORCEPROP 1 LAST PATH I139
J 0
(3173 3575);
DISPLAY 0.872340 (3173 3575);
PAINT GREEN (3173 3575);
DISPLAY INVISIBLE (3173 3575);
FORCEADD TAP..1
(3175 3625);
FORCEPROP 3 LASTPIN (3125 3625) SIG_NAME UPI_CPU0_CPU1_P0P1_DN<22>
J 0
(3135 3635);
DISPLAY 0.659574 (3135 3635);
PAINT MONO (3135 3635);
DISPLAY INVISIBLE (3135 3635);
FORCEPROP 1 LASTPIN (3125 3625) BN 22
J 0
(3113 3633);
DISPLAY 0.680851 (3113 3633);
PAINT GREEN (3113 3633);
FORCEPROP 2 LAST CDS_LIB standard
J 0
(3175 3625);
DISPLAY INVISIBLE (3175 3625);
FORCEPROP 1 LAST BODY_TYPE PLUMBING
J 0
(3175 3675);
DISPLAY 0.872340 (3175 3675);
PAINT GREEN (3175 3675);
DISPLAY INVISIBLE (3175 3675);
FORCEPROP 1 LAST HDL_TAP TRUE
J 0
(3500 3500);
DISPLAY 0.872340 (3500 3500);
DISPLAY INVISIBLE (3500 3500);
FORCEPROP 1 LAST PATH I140
J 0
(3173 3625);
DISPLAY 0.872340 (3173 3625);
PAINT GREEN (3173 3625);
DISPLAY INVISIBLE (3173 3625);
FORCEADD TAP..1
(3175 3525);
FORCEPROP 3 LASTPIN (3125 3525) SIG_NAME UPI_CPU0_CPU1_P0P1_DN<20>
J 0
(3135 3535);
DISPLAY 0.659574 (3135 3535);
PAINT MONO (3135 3535);
DISPLAY INVISIBLE (3135 3535);
FORCEPROP 1 LASTPIN (3125 3525) BN 20
J 0
(3113 3533);
DISPLAY 0.680851 (3113 3533);
PAINT GREEN (3113 3533);
FORCEPROP 2 LAST CDS_LIB standard
J 0
(3175 3525);
DISPLAY INVISIBLE (3175 3525);
FORCEPROP 1 LAST BODY_TYPE PLUMBING
J 0
(3175 3575);
DISPLAY 0.872340 (3175 3575);
PAINT GREEN (3175 3575);
DISPLAY INVISIBLE (3175 3575);
FORCEPROP 1 LAST HDL_TAP TRUE
J 0
(3500 3400);
DISPLAY 0.872340 (3500 3400);
DISPLAY INVISIBLE (3500 3400);
FORCEPROP 1 LAST PATH I141
J 0
(3173 3525);
DISPLAY 0.872340 (3173 3525);
PAINT GREEN (3173 3525);
DISPLAY INVISIBLE (3173 3525);
FORCEADD TAP..1
(3175 3175);
FORCEPROP 3 LASTPIN (3125 3175) SIG_NAME UPI_CPU0_CPU1_P0P1_DN<13>
J 0
(3135 3185);
DISPLAY 0.659574 (3135 3185);
PAINT MONO (3135 3185);
DISPLAY INVISIBLE (3135 3185);
FORCEPROP 1 LASTPIN (3125 3175) BN 13
J 0
(3113 3183);
DISPLAY 0.680851 (3113 3183);
PAINT GREEN (3113 3183);
FORCEPROP 2 LAST CDS_LIB standard
J 0
(3175 3175);
PAINT MONO (3175 3175);
DISPLAY INVISIBLE (3175 3175);
FORCEPROP 1 LAST BODY_TYPE PLUMBING
J 0
(3175 3225);
DISPLAY 0.872340 (3175 3225);
PAINT GREEN (3175 3225);
DISPLAY INVISIBLE (3175 3225);
FORCEPROP 1 LAST HDL_TAP TRUE
J 0
(3500 3050);
DISPLAY 0.872340 (3500 3050);
DISPLAY INVISIBLE (3500 3050);
FORCEPROP 1 LAST PATH I142
J 0
(3173 3175);
DISPLAY 0.872340 (3173 3175);
PAINT GREEN (3173 3175);
DISPLAY INVISIBLE (3173 3175);
FORCEADD TAP..1
(3175 3275);
FORCEPROP 3 LASTPIN (3125 3275) SIG_NAME UPI_CPU0_CPU1_P0P1_DN<15>
J 0
(3135 3285);
DISPLAY 0.659574 (3135 3285);
PAINT MONO (3135 3285);
DISPLAY INVISIBLE (3135 3285);
FORCEPROP 1 LASTPIN (3125 3275) BN 15
J 0
(3113 3283);
DISPLAY 0.680851 (3113 3283);
PAINT GREEN (3113 3283);
FORCEPROP 2 LAST CDS_LIB standard
J 0
(3175 3275);
PAINT MONO (3175 3275);
DISPLAY INVISIBLE (3175 3275);
FORCEPROP 1 LAST BODY_TYPE PLUMBING
J 0
(3175 3325);
DISPLAY 0.872340 (3175 3325);
PAINT GREEN (3175 3325);
DISPLAY INVISIBLE (3175 3325);
FORCEPROP 1 LAST HDL_TAP TRUE
J 0
(3500 3150);
DISPLAY 0.872340 (3500 3150);
DISPLAY INVISIBLE (3500 3150);
FORCEPROP 1 LAST PATH I143
J 0
(3173 3275);
DISPLAY 0.872340 (3173 3275);
PAINT GREEN (3173 3275);
DISPLAY INVISIBLE (3173 3275);
FORCEADD TAP..1
(3175 3125);
FORCEPROP 3 LASTPIN (3125 3125) SIG_NAME UPI_CPU0_CPU1_P0P1_DN<12>
J 0
(3135 3135);
DISPLAY 0.659574 (3135 3135);
PAINT MONO (3135 3135);
DISPLAY INVISIBLE (3135 3135);
FORCEPROP 1 LASTPIN (3125 3125) BN 12
J 0
(3113 3133);
DISPLAY 0.680851 (3113 3133);
PAINT GREEN (3113 3133);
FORCEPROP 2 LAST CDS_LIB standard
J 0
(3175 3125);
PAINT MONO (3175 3125);
DISPLAY INVISIBLE (3175 3125);
FORCEPROP 1 LAST BODY_TYPE PLUMBING
J 0
(3175 3175);
DISPLAY 0.872340 (3175 3175);
PAINT GREEN (3175 3175);
DISPLAY INVISIBLE (3175 3175);
FORCEPROP 1 LAST HDL_TAP TRUE
J 0
(3500 3000);
DISPLAY 0.872340 (3500 3000);
DISPLAY INVISIBLE (3500 3000);
FORCEPROP 1 LAST PATH I144
J 0
(3173 3125);
DISPLAY 0.872340 (3173 3125);
PAINT GREEN (3173 3125);
DISPLAY INVISIBLE (3173 3125);
FORCEADD OFFPAGE..2
(4175 2500);
FORCEPROP 2 LAST $XR0 64 
J 0
(4364 2500);
DISPLAY 0.638298 (4364 2500);
PAINT MONO (4364 2500);
FORCEPROP 2 LAST CDS_LIB standard
J 0
(4175 2500);
PAINT MONO (4175 2500);
DISPLAY INVISIBLE (4175 2500);
FORCEPROP 1 LAST OFFPAGE TRUE
J 0
(4500 2375);
DISPLAY 1.170213 (4500 2375);
PAINT GREEN (4500 2375);
DISPLAY INVISIBLE (4500 2375);
FORCEPROP 1 LAST COMMENT_BODY TRUE
J 0
(4130 2405);
DISPLAY 1.170213 (4130 2405);
PAINT GREEN (4130 2405);
DISPLAY INVISIBLE (4130 2405);
FORCEPROP 2 LAST PATH I145
J 0
(4375 2550);
DISPLAY 1.021277 (4375 2550);
DISPLAY INVISIBLE (4375 2550);
FORCEADD TAP..1
R 2
(-575 3125);
FORCEPROP 3 LASTPIN (-525 3125) SIG_NAME UPI_CPU1_CPU0_P1P0_DN<12>
J 0
(-515 3135);
DISPLAY 0.659574 (-515 3135);
PAINT MONO (-515 3135);
DISPLAY INVISIBLE (-515 3135);
FORCEPROP 1 LASTPIN (-525 3125) BN 12
J 2
(-513 3133);
DISPLAY 0.680851 (-513 3133);
PAINT GREEN (-513 3133);
FORCEPROP 2 LAST CDS_LIB standard
J 0
(-575 3125);
DISPLAY INVISIBLE (-575 3125);
FORCEPROP 1 LAST BODY_TYPE PLUMBING
J 2
(-575 3175);
DISPLAY 0.872340 (-575 3175);
PAINT GREEN (-575 3175);
DISPLAY INVISIBLE (-575 3175);
FORCEPROP 1 LAST HDL_TAP TRUE
J 2
(-900 3000);
DISPLAY 0.872340 (-900 3000);
DISPLAY INVISIBLE (-900 3000);
FORCEPROP 1 LAST PATH I146
J 2
(-573 3125);
DISPLAY 0.872340 (-573 3125);
PAINT GREEN (-573 3125);
DISPLAY INVISIBLE (-573 3125);
FORCEADD TAP..1
R 2
(-400 1875);
FORCEPROP 3 LASTPIN (-350 1875) SIG_NAME UPI_CPU1_CPU0_P1P0_DP<12>
J 0
(-340 1885);
DISPLAY 0.659574 (-340 1885);
PAINT MONO (-340 1885);
DISPLAY INVISIBLE (-340 1885);
FORCEPROP 1 LASTPIN (-350 1875) BN 12
J 2
(-338 1883);
DISPLAY 0.680851 (-338 1883);
PAINT GREEN (-338 1883);
FORCEPROP 2 LAST CDS_LIB standard
J 0
(-400 1875);
DISPLAY INVISIBLE (-400 1875);
FORCEPROP 1 LAST BODY_TYPE PLUMBING
J 2
(-400 1925);
DISPLAY 0.872340 (-400 1925);
PAINT GREEN (-400 1925);
DISPLAY INVISIBLE (-400 1925);
FORCEPROP 1 LAST HDL_TAP TRUE
J 2
(-725 1750);
DISPLAY 0.872340 (-725 1750);
DISPLAY INVISIBLE (-725 1750);
FORCEPROP 1 LAST PATH I147
J 2
(-398 1875);
DISPLAY 0.872340 (-398 1875);
PAINT GREEN (-398 1875);
DISPLAY INVISIBLE (-398 1875);
FORCEADD TAP..1
R 2
(-575 3175);
FORCEPROP 3 LASTPIN (-525 3175) SIG_NAME UPI_CPU1_CPU0_P1P0_DN<13>
J 0
(-515 3185);
DISPLAY 0.659574 (-515 3185);
PAINT MONO (-515 3185);
DISPLAY INVISIBLE (-515 3185);
FORCEPROP 1 LASTPIN (-525 3175) BN 13
J 2
(-513 3183);
DISPLAY 0.680851 (-513 3183);
PAINT GREEN (-513 3183);
FORCEPROP 2 LAST CDS_LIB standard
J 0
(-575 3175);
DISPLAY INVISIBLE (-575 3175);
FORCEPROP 1 LAST BODY_TYPE PLUMBING
J 2
(-575 3225);
DISPLAY 0.872340 (-575 3225);
PAINT GREEN (-575 3225);
DISPLAY INVISIBLE (-575 3225);
FORCEPROP 1 LAST HDL_TAP TRUE
J 2
(-900 3050);
DISPLAY 0.872340 (-900 3050);
DISPLAY INVISIBLE (-900 3050);
FORCEPROP 1 LAST PATH I148
J 2
(-573 3175);
DISPLAY 0.872340 (-573 3175);
PAINT GREEN (-573 3175);
DISPLAY INVISIBLE (-573 3175);
FORCEADD TAP..1
R 2
(-400 1925);
FORCEPROP 3 LASTPIN (-350 1925) SIG_NAME UPI_CPU1_CPU0_P1P0_DP<13>
J 0
(-340 1935);
DISPLAY 0.659574 (-340 1935);
PAINT MONO (-340 1935);
DISPLAY INVISIBLE (-340 1935);
FORCEPROP 1 LASTPIN (-350 1925) BN 13
J 2
(-338 1933);
DISPLAY 0.680851 (-338 1933);
PAINT GREEN (-338 1933);
FORCEPROP 2 LAST CDS_LIB standard
J 0
(-400 1925);
DISPLAY INVISIBLE (-400 1925);
FORCEPROP 1 LAST BODY_TYPE PLUMBING
J 2
(-400 1975);
DISPLAY 0.872340 (-400 1975);
PAINT GREEN (-400 1975);
DISPLAY INVISIBLE (-400 1975);
FORCEPROP 1 LAST HDL_TAP TRUE
J 2
(-725 1800);
DISPLAY 0.872340 (-725 1800);
DISPLAY INVISIBLE (-725 1800);
FORCEPROP 1 LAST PATH I149
J 2
(-398 1925);
DISPLAY 0.872340 (-398 1925);
PAINT GREEN (-398 1925);
DISPLAY INVISIBLE (-398 1925);
FORCEADD TAP..1
R 2
(-575 3525);
FORCEPROP 3 LASTPIN (-525 3525) SIG_NAME UPI_CPU1_CPU0_P1P0_DN<20>
J 0
(-515 3535);
DISPLAY 0.659574 (-515 3535);
PAINT MONO (-515 3535);
DISPLAY INVISIBLE (-515 3535);
FORCEPROP 1 LASTPIN (-525 3525) BN 20
J 2
(-513 3533);
DISPLAY 0.680851 (-513 3533);
PAINT GREEN (-513 3533);
FORCEPROP 2 LAST CDS_LIB standard
J 0
(-575 3525);
DISPLAY INVISIBLE (-575 3525);
FORCEPROP 1 LAST BODY_TYPE PLUMBING
J 2
(-575 3575);
DISPLAY 0.872340 (-575 3575);
PAINT GREEN (-575 3575);
DISPLAY INVISIBLE (-575 3575);
FORCEPROP 1 LAST HDL_TAP TRUE
J 2
(-900 3400);
DISPLAY 0.872340 (-900 3400);
DISPLAY INVISIBLE (-900 3400);
FORCEPROP 1 LAST PATH I150
J 2
(-573 3525);
DISPLAY 0.872340 (-573 3525);
PAINT GREEN (-573 3525);
DISPLAY INVISIBLE (-573 3525);
FORCEADD TAP..1
R 2
(-575 3475);
FORCEPROP 3 LASTPIN (-525 3475) SIG_NAME UPI_CPU1_CPU0_P1P0_DN<19>
J 0
(-515 3485);
DISPLAY 0.659574 (-515 3485);
PAINT MONO (-515 3485);
DISPLAY INVISIBLE (-515 3485);
FORCEPROP 1 LASTPIN (-525 3475) BN 19
J 2
(-513 3483);
DISPLAY 0.680851 (-513 3483);
PAINT GREEN (-513 3483);
FORCEPROP 2 LAST CDS_LIB standard
J 0
(-575 3475);
DISPLAY INVISIBLE (-575 3475);
FORCEPROP 1 LAST BODY_TYPE PLUMBING
J 2
(-575 3525);
DISPLAY 0.872340 (-575 3525);
PAINT GREEN (-575 3525);
DISPLAY INVISIBLE (-575 3525);
FORCEPROP 1 LAST HDL_TAP TRUE
J 2
(-900 3350);
DISPLAY 0.872340 (-900 3350);
DISPLAY INVISIBLE (-900 3350);
FORCEPROP 1 LAST PATH I151
J 2
(-573 3475);
DISPLAY 0.872340 (-573 3475);
PAINT GREEN (-573 3475);
DISPLAY INVISIBLE (-573 3475);
FORCEADD TAP..1
R 2
(-575 3425);
FORCEPROP 3 LASTPIN (-525 3425) SIG_NAME UPI_CPU1_CPU0_P1P0_DN<18>
J 0
(-515 3435);
DISPLAY 0.659574 (-515 3435);
PAINT MONO (-515 3435);
DISPLAY INVISIBLE (-515 3435);
FORCEPROP 1 LASTPIN (-525 3425) BN 18
J 2
(-513 3433);
DISPLAY 0.680851 (-513 3433);
PAINT GREEN (-513 3433);
FORCEPROP 2 LAST CDS_LIB standard
J 0
(-575 3425);
DISPLAY INVISIBLE (-575 3425);
FORCEPROP 1 LAST BODY_TYPE PLUMBING
J 2
(-575 3475);
DISPLAY 0.872340 (-575 3475);
PAINT GREEN (-575 3475);
DISPLAY INVISIBLE (-575 3475);
FORCEPROP 1 LAST HDL_TAP TRUE
J 2
(-900 3300);
DISPLAY 0.872340 (-900 3300);
DISPLAY INVISIBLE (-900 3300);
FORCEPROP 1 LAST PATH I152
J 2
(-573 3425);
DISPLAY 0.872340 (-573 3425);
PAINT GREEN (-573 3425);
DISPLAY INVISIBLE (-573 3425);
FORCEADD TAP..1
R 2
(-575 3375);
FORCEPROP 3 LASTPIN (-525 3375) SIG_NAME UPI_CPU1_CPU0_P1P0_DN<17>
J 0
(-515 3385);
DISPLAY 0.659574 (-515 3385);
PAINT MONO (-515 3385);
DISPLAY INVISIBLE (-515 3385);
FORCEPROP 1 LASTPIN (-525 3375) BN 17
J 2
(-513 3383);
DISPLAY 0.680851 (-513 3383);
PAINT GREEN (-513 3383);
FORCEPROP 2 LAST CDS_LIB standard
J 0
(-575 3375);
DISPLAY INVISIBLE (-575 3375);
FORCEPROP 1 LAST BODY_TYPE PLUMBING
J 2
(-575 3425);
DISPLAY 0.872340 (-575 3425);
PAINT GREEN (-575 3425);
DISPLAY INVISIBLE (-575 3425);
FORCEPROP 1 LAST HDL_TAP TRUE
J 2
(-900 3250);
DISPLAY 0.872340 (-900 3250);
DISPLAY INVISIBLE (-900 3250);
FORCEPROP 1 LAST PATH I153
J 2
(-573 3375);
DISPLAY 0.872340 (-573 3375);
PAINT GREEN (-573 3375);
DISPLAY INVISIBLE (-573 3375);
FORCEADD TAP..1
R 2
(-575 3325);
FORCEPROP 3 LASTPIN (-525 3325) SIG_NAME UPI_CPU1_CPU0_P1P0_DN<16>
J 0
(-515 3335);
DISPLAY 0.659574 (-515 3335);
PAINT MONO (-515 3335);
DISPLAY INVISIBLE (-515 3335);
FORCEPROP 1 LASTPIN (-525 3325) BN 16
J 2
(-513 3333);
DISPLAY 0.680851 (-513 3333);
PAINT GREEN (-513 3333);
FORCEPROP 2 LAST CDS_LIB standard
J 0
(-575 3325);
DISPLAY INVISIBLE (-575 3325);
FORCEPROP 1 LAST BODY_TYPE PLUMBING
J 2
(-575 3375);
DISPLAY 0.872340 (-575 3375);
PAINT GREEN (-575 3375);
DISPLAY INVISIBLE (-575 3375);
FORCEPROP 1 LAST HDL_TAP TRUE
J 2
(-900 3200);
DISPLAY 0.872340 (-900 3200);
DISPLAY INVISIBLE (-900 3200);
FORCEPROP 1 LAST PATH I154
J 2
(-573 3325);
DISPLAY 0.872340 (-573 3325);
PAINT GREEN (-573 3325);
DISPLAY INVISIBLE (-573 3325);
FORCEADD TAP..1
R 2
(-575 3275);
FORCEPROP 3 LASTPIN (-525 3275) SIG_NAME UPI_CPU1_CPU0_P1P0_DN<15>
J 0
(-515 3285);
DISPLAY 0.659574 (-515 3285);
PAINT MONO (-515 3285);
DISPLAY INVISIBLE (-515 3285);
FORCEPROP 1 LASTPIN (-525 3275) BN 15
J 2
(-513 3283);
DISPLAY 0.680851 (-513 3283);
PAINT GREEN (-513 3283);
FORCEPROP 2 LAST CDS_LIB standard
J 0
(-575 3275);
DISPLAY INVISIBLE (-575 3275);
FORCEPROP 1 LAST BODY_TYPE PLUMBING
J 2
(-575 3325);
DISPLAY 0.872340 (-575 3325);
PAINT GREEN (-575 3325);
DISPLAY INVISIBLE (-575 3325);
FORCEPROP 1 LAST HDL_TAP TRUE
J 2
(-900 3150);
DISPLAY 0.872340 (-900 3150);
DISPLAY INVISIBLE (-900 3150);
FORCEPROP 1 LAST PATH I155
J 2
(-573 3275);
DISPLAY 0.872340 (-573 3275);
PAINT GREEN (-573 3275);
DISPLAY INVISIBLE (-573 3275);
FORCEADD TAP..1
R 2
(-575 3225);
FORCEPROP 3 LASTPIN (-525 3225) SIG_NAME UPI_CPU1_CPU0_P1P0_DN<14>
J 0
(-515 3235);
DISPLAY 0.659574 (-515 3235);
PAINT MONO (-515 3235);
DISPLAY INVISIBLE (-515 3235);
FORCEPROP 1 LASTPIN (-525 3225) BN 14
J 2
(-513 3233);
DISPLAY 0.680851 (-513 3233);
PAINT GREEN (-513 3233);
FORCEPROP 2 LAST CDS_LIB standard
J 0
(-575 3225);
DISPLAY INVISIBLE (-575 3225);
FORCEPROP 1 LAST BODY_TYPE PLUMBING
J 2
(-575 3275);
DISPLAY 0.872340 (-575 3275);
PAINT GREEN (-575 3275);
DISPLAY INVISIBLE (-575 3275);
FORCEPROP 1 LAST HDL_TAP TRUE
J 2
(-900 3100);
DISPLAY 0.872340 (-900 3100);
DISPLAY INVISIBLE (-900 3100);
FORCEPROP 1 LAST PATH I156
J 2
(-573 3225);
DISPLAY 0.872340 (-573 3225);
PAINT GREEN (-573 3225);
DISPLAY INVISIBLE (-573 3225);
FORCEADD TAP..1
R 2
(-400 2275);
FORCEPROP 3 LASTPIN (-350 2275) SIG_NAME UPI_CPU1_CPU0_P1P0_DP<20>
J 0
(-340 2285);
DISPLAY 0.659574 (-340 2285);
PAINT MONO (-340 2285);
DISPLAY INVISIBLE (-340 2285);
FORCEPROP 1 LASTPIN (-350 2275) BN 20
J 2
(-338 2283);
DISPLAY 0.680851 (-338 2283);
PAINT GREEN (-338 2283);
FORCEPROP 2 LAST CDS_LIB standard
J 0
(-400 2275);
DISPLAY INVISIBLE (-400 2275);
FORCEPROP 1 LAST BODY_TYPE PLUMBING
J 2
(-400 2325);
DISPLAY 0.872340 (-400 2325);
PAINT GREEN (-400 2325);
DISPLAY INVISIBLE (-400 2325);
FORCEPROP 1 LAST HDL_TAP TRUE
J 2
(-725 2150);
DISPLAY 0.872340 (-725 2150);
DISPLAY INVISIBLE (-725 2150);
FORCEPROP 1 LAST PATH I157
J 2
(-398 2275);
DISPLAY 0.872340 (-398 2275);
PAINT GREEN (-398 2275);
DISPLAY INVISIBLE (-398 2275);
FORCEADD TAP..1
R 2
(-400 2225);
FORCEPROP 3 LASTPIN (-350 2225) SIG_NAME UPI_CPU1_CPU0_P1P0_DP<19>
J 0
(-340 2235);
DISPLAY 0.659574 (-340 2235);
PAINT MONO (-340 2235);
DISPLAY INVISIBLE (-340 2235);
FORCEPROP 1 LASTPIN (-350 2225) BN 19
J 2
(-338 2233);
DISPLAY 0.680851 (-338 2233);
PAINT GREEN (-338 2233);
FORCEPROP 2 LAST CDS_LIB standard
J 0
(-400 2225);
DISPLAY INVISIBLE (-400 2225);
FORCEPROP 1 LAST BODY_TYPE PLUMBING
J 2
(-400 2275);
DISPLAY 0.872340 (-400 2275);
PAINT GREEN (-400 2275);
DISPLAY INVISIBLE (-400 2275);
FORCEPROP 1 LAST HDL_TAP TRUE
J 2
(-725 2100);
DISPLAY 0.872340 (-725 2100);
DISPLAY INVISIBLE (-725 2100);
FORCEPROP 1 LAST PATH I158
J 2
(-398 2225);
DISPLAY 0.872340 (-398 2225);
PAINT GREEN (-398 2225);
DISPLAY INVISIBLE (-398 2225);
FORCEADD TAP..1
R 2
(-400 2175);
FORCEPROP 3 LASTPIN (-350 2175) SIG_NAME UPI_CPU1_CPU0_P1P0_DP<18>
J 0
(-340 2185);
DISPLAY 0.659574 (-340 2185);
PAINT MONO (-340 2185);
DISPLAY INVISIBLE (-340 2185);
FORCEPROP 1 LASTPIN (-350 2175) BN 18
J 2
(-338 2183);
DISPLAY 0.680851 (-338 2183);
PAINT GREEN (-338 2183);
FORCEPROP 2 LAST CDS_LIB standard
J 0
(-400 2175);
DISPLAY INVISIBLE (-400 2175);
FORCEPROP 1 LAST BODY_TYPE PLUMBING
J 2
(-400 2225);
DISPLAY 0.872340 (-400 2225);
PAINT GREEN (-400 2225);
DISPLAY INVISIBLE (-400 2225);
FORCEPROP 1 LAST HDL_TAP TRUE
J 2
(-725 2050);
DISPLAY 0.872340 (-725 2050);
DISPLAY INVISIBLE (-725 2050);
FORCEPROP 1 LAST PATH I159
J 2
(-398 2175);
DISPLAY 0.872340 (-398 2175);
PAINT GREEN (-398 2175);
DISPLAY INVISIBLE (-398 2175);
FORCEADD TAP..1
R 2
(-400 2125);
FORCEPROP 3 LASTPIN (-350 2125) SIG_NAME UPI_CPU1_CPU0_P1P0_DP<17>
J 0
(-340 2135);
DISPLAY 0.659574 (-340 2135);
PAINT MONO (-340 2135);
DISPLAY INVISIBLE (-340 2135);
FORCEPROP 1 LASTPIN (-350 2125) BN 17
J 2
(-338 2133);
DISPLAY 0.680851 (-338 2133);
PAINT GREEN (-338 2133);
FORCEPROP 2 LAST CDS_LIB standard
J 0
(-400 2125);
DISPLAY INVISIBLE (-400 2125);
FORCEPROP 1 LAST BODY_TYPE PLUMBING
J 2
(-400 2175);
DISPLAY 0.872340 (-400 2175);
PAINT GREEN (-400 2175);
DISPLAY INVISIBLE (-400 2175);
FORCEPROP 1 LAST HDL_TAP TRUE
J 2
(-725 2000);
DISPLAY 0.872340 (-725 2000);
DISPLAY INVISIBLE (-725 2000);
FORCEPROP 1 LAST PATH I160
J 2
(-398 2125);
DISPLAY 0.872340 (-398 2125);
PAINT GREEN (-398 2125);
DISPLAY INVISIBLE (-398 2125);
FORCEADD TAP..1
R 2
(-400 2075);
FORCEPROP 3 LASTPIN (-350 2075) SIG_NAME UPI_CPU1_CPU0_P1P0_DP<16>
J 0
(-340 2085);
DISPLAY 0.659574 (-340 2085);
PAINT MONO (-340 2085);
DISPLAY INVISIBLE (-340 2085);
FORCEPROP 1 LASTPIN (-350 2075) BN 16
J 2
(-338 2083);
DISPLAY 0.680851 (-338 2083);
PAINT GREEN (-338 2083);
FORCEPROP 2 LAST CDS_LIB standard
J 0
(-400 2075);
DISPLAY INVISIBLE (-400 2075);
FORCEPROP 1 LAST BODY_TYPE PLUMBING
J 2
(-400 2125);
DISPLAY 0.872340 (-400 2125);
PAINT GREEN (-400 2125);
DISPLAY INVISIBLE (-400 2125);
FORCEPROP 1 LAST HDL_TAP TRUE
J 2
(-725 1950);
DISPLAY 0.872340 (-725 1950);
DISPLAY INVISIBLE (-725 1950);
FORCEPROP 1 LAST PATH I161
J 2
(-398 2075);
DISPLAY 0.872340 (-398 2075);
PAINT GREEN (-398 2075);
DISPLAY INVISIBLE (-398 2075);
FORCEADD TAP..1
R 2
(-400 2025);
FORCEPROP 3 LASTPIN (-350 2025) SIG_NAME UPI_CPU1_CPU0_P1P0_DP<15>
J 0
(-340 2035);
DISPLAY 0.659574 (-340 2035);
PAINT MONO (-340 2035);
DISPLAY INVISIBLE (-340 2035);
FORCEPROP 1 LASTPIN (-350 2025) BN 15
J 2
(-338 2033);
DISPLAY 0.680851 (-338 2033);
PAINT GREEN (-338 2033);
FORCEPROP 2 LAST CDS_LIB standard
J 0
(-400 2025);
DISPLAY INVISIBLE (-400 2025);
FORCEPROP 1 LAST BODY_TYPE PLUMBING
J 2
(-400 2075);
DISPLAY 0.872340 (-400 2075);
PAINT GREEN (-400 2075);
DISPLAY INVISIBLE (-400 2075);
FORCEPROP 1 LAST HDL_TAP TRUE
J 2
(-725 1900);
DISPLAY 0.872340 (-725 1900);
DISPLAY INVISIBLE (-725 1900);
FORCEPROP 1 LAST PATH I162
J 2
(-398 2025);
DISPLAY 0.872340 (-398 2025);
PAINT GREEN (-398 2025);
DISPLAY INVISIBLE (-398 2025);
FORCEADD TAP..1
R 2
(-400 1975);
FORCEPROP 3 LASTPIN (-350 1975) SIG_NAME UPI_CPU1_CPU0_P1P0_DP<14>
J 0
(-340 1985);
DISPLAY 0.659574 (-340 1985);
PAINT MONO (-340 1985);
DISPLAY INVISIBLE (-340 1985);
FORCEPROP 1 LASTPIN (-350 1975) BN 14
J 2
(-338 1983);
DISPLAY 0.680851 (-338 1983);
PAINT GREEN (-338 1983);
FORCEPROP 2 LAST CDS_LIB standard
J 0
(-400 1975);
DISPLAY INVISIBLE (-400 1975);
FORCEPROP 1 LAST BODY_TYPE PLUMBING
J 2
(-400 2025);
DISPLAY 0.872340 (-400 2025);
PAINT GREEN (-400 2025);
DISPLAY INVISIBLE (-400 2025);
FORCEPROP 1 LAST HDL_TAP TRUE
J 2
(-725 1850);
DISPLAY 0.872340 (-725 1850);
DISPLAY INVISIBLE (-725 1850);
FORCEPROP 1 LAST PATH I163
J 2
(-398 1975);
DISPLAY 0.872340 (-398 1975);
PAINT GREEN (-398 1975);
DISPLAY INVISIBLE (-398 1975);
FORCEADD OFFPAGE..1
(-1800 2500);
FORCEPROP 2 LAST $XR0 64 
J 0
(-2051 2500);
DISPLAY 0.638298 (-2051 2500);
PAINT MONO (-2051 2500);
FORCEPROP 2 LAST CDS_LIB standard
J 0
(-1800 2500);
PAINT MONO (-1800 2500);
DISPLAY INVISIBLE (-1800 2500);
FORCEPROP 1 LAST OFFPAGE TRUE
J 0
(-1475 2375);
DISPLAY 0.872340 (-1475 2375);
DISPLAY INVISIBLE (-1475 2375);
FORCEPROP 1 LAST COMMENT_BODY TRUE
J 0
(-1675 2400);
DISPLAY 0.872340 (-1675 2400);
PAINT GREEN (-1675 2400);
DISPLAY INVISIBLE (-1675 2400);
FORCEPROP 2 LAST PATH I164
J 0
(-2050 2550);
DISPLAY 1.021277 (-2050 2550);
DISPLAY INVISIBLE (-2050 2550);
FORCEADD TAP..1
R 2
(-575 3675);
FORCEPROP 3 LASTPIN (-525 3675) SIG_NAME UPI_CPU1_CPU0_P1P0_DN<23>
J 0
(-515 3685);
DISPLAY 0.659574 (-515 3685);
PAINT MONO (-515 3685);
DISPLAY INVISIBLE (-515 3685);
FORCEPROP 1 LASTPIN (-525 3675) BN 23
J 2
(-513 3683);
DISPLAY 0.680851 (-513 3683);
PAINT GREEN (-513 3683);
FORCEPROP 2 LAST CDS_LIB standard
J 0
(-575 3675);
DISPLAY INVISIBLE (-575 3675);
FORCEPROP 1 LAST BODY_TYPE PLUMBING
J 2
(-575 3725);
DISPLAY 0.872340 (-575 3725);
PAINT GREEN (-575 3725);
DISPLAY INVISIBLE (-575 3725);
FORCEPROP 1 LAST HDL_TAP TRUE
J 2
(-900 3550);
DISPLAY 0.872340 (-900 3550);
DISPLAY INVISIBLE (-900 3550);
FORCEPROP 1 LAST PATH I165
J 2
(-573 3675);
DISPLAY 0.872340 (-573 3675);
PAINT GREEN (-573 3675);
DISPLAY INVISIBLE (-573 3675);
FORCEADD TAP..1
R 2
(-575 3575);
FORCEPROP 3 LASTPIN (-525 3575) SIG_NAME UPI_CPU1_CPU0_P1P0_DN<21>
J 0
(-515 3585);
DISPLAY 0.659574 (-515 3585);
PAINT MONO (-515 3585);
DISPLAY INVISIBLE (-515 3585);
FORCEPROP 1 LASTPIN (-525 3575) BN 21
J 2
(-513 3583);
DISPLAY 0.680851 (-513 3583);
PAINT GREEN (-513 3583);
FORCEPROP 2 LAST CDS_LIB standard
J 0
(-575 3575);
DISPLAY INVISIBLE (-575 3575);
FORCEPROP 1 LAST BODY_TYPE PLUMBING
J 2
(-575 3625);
DISPLAY 0.872340 (-575 3625);
PAINT GREEN (-575 3625);
DISPLAY INVISIBLE (-575 3625);
FORCEPROP 1 LAST HDL_TAP TRUE
J 2
(-900 3450);
DISPLAY 0.872340 (-900 3450);
DISPLAY INVISIBLE (-900 3450);
FORCEPROP 1 LAST PATH I166
J 2
(-573 3575);
DISPLAY 0.872340 (-573 3575);
PAINT GREEN (-573 3575);
DISPLAY INVISIBLE (-573 3575);
FORCEADD TAP..1
R 2
(-400 2425);
FORCEPROP 3 LASTPIN (-350 2425) SIG_NAME UPI_CPU1_CPU0_P1P0_DP<23>
J 0
(-340 2435);
DISPLAY 0.659574 (-340 2435);
PAINT MONO (-340 2435);
DISPLAY INVISIBLE (-340 2435);
FORCEPROP 1 LASTPIN (-350 2425) BN 23
J 2
(-338 2433);
DISPLAY 0.680851 (-338 2433);
PAINT GREEN (-338 2433);
FORCEPROP 2 LAST CDS_LIB standard
J 0
(-400 2425);
DISPLAY INVISIBLE (-400 2425);
FORCEPROP 1 LAST BODY_TYPE PLUMBING
J 2
(-400 2475);
DISPLAY 0.872340 (-400 2475);
PAINT GREEN (-400 2475);
DISPLAY INVISIBLE (-400 2475);
FORCEPROP 1 LAST HDL_TAP TRUE
J 2
(-725 2300);
DISPLAY 0.872340 (-725 2300);
DISPLAY INVISIBLE (-725 2300);
FORCEPROP 1 LAST PATH I167
J 2
(-398 2425);
DISPLAY 0.872340 (-398 2425);
PAINT GREEN (-398 2425);
DISPLAY INVISIBLE (-398 2425);
FORCEADD TAP..1
R 2
(-400 2325);
FORCEPROP 3 LASTPIN (-350 2325) SIG_NAME UPI_CPU1_CPU0_P1P0_DP<21>
J 0
(-340 2335);
DISPLAY 0.659574 (-340 2335);
PAINT MONO (-340 2335);
DISPLAY INVISIBLE (-340 2335);
FORCEPROP 1 LASTPIN (-350 2325) BN 21
J 2
(-338 2333);
DISPLAY 0.680851 (-338 2333);
PAINT GREEN (-338 2333);
FORCEPROP 2 LAST CDS_LIB standard
J 0
(-400 2325);
DISPLAY INVISIBLE (-400 2325);
FORCEPROP 1 LAST BODY_TYPE PLUMBING
J 2
(-400 2375);
DISPLAY 0.872340 (-400 2375);
PAINT GREEN (-400 2375);
DISPLAY INVISIBLE (-400 2375);
FORCEPROP 1 LAST HDL_TAP TRUE
J 2
(-725 2200);
DISPLAY 0.872340 (-725 2200);
DISPLAY INVISIBLE (-725 2200);
FORCEPROP 1 LAST PATH I168
J 2
(-398 2325);
DISPLAY 0.872340 (-398 2325);
PAINT GREEN (-398 2325);
DISPLAY INVISIBLE (-398 2325);
FORCEADD TAP..1
R 2
(-575 3025);
FORCEPROP 3 LASTPIN (-525 3025) SIG_NAME UPI_CPU1_CPU0_P1P0_DN<10>
J 0
(-515 3035);
DISPLAY 0.659574 (-515 3035);
PAINT MONO (-515 3035);
DISPLAY INVISIBLE (-515 3035);
FORCEPROP 1 LASTPIN (-525 3025) BN 10
J 2
(-513 3033);
DISPLAY 0.680851 (-513 3033);
PAINT GREEN (-513 3033);
FORCEPROP 2 LAST CDS_LIB standard
J 0
(-575 3025);
DISPLAY INVISIBLE (-575 3025);
FORCEPROP 1 LAST BODY_TYPE PLUMBING
J 2
(-575 3075);
DISPLAY 0.872340 (-575 3075);
PAINT GREEN (-575 3075);
DISPLAY INVISIBLE (-575 3075);
FORCEPROP 1 LAST HDL_TAP TRUE
J 2
(-900 2900);
DISPLAY 0.872340 (-900 2900);
DISPLAY INVISIBLE (-900 2900);
FORCEPROP 1 LAST PATH I169
J 2
(-573 3025);
DISPLAY 0.872340 (-573 3025);
PAINT GREEN (-573 3025);
DISPLAY INVISIBLE (-573 3025);
FORCEADD TAP..1
R 2
(-575 3075);
FORCEPROP 3 LASTPIN (-525 3075) SIG_NAME UPI_CPU1_CPU0_P1P0_DN<11>
J 0
(-515 3085);
DISPLAY 0.659574 (-515 3085);
PAINT MONO (-515 3085);
DISPLAY INVISIBLE (-515 3085);
FORCEPROP 1 LASTPIN (-525 3075) BN 11
J 2
(-513 3083);
DISPLAY 0.680851 (-513 3083);
PAINT GREEN (-513 3083);
FORCEPROP 2 LAST CDS_LIB standard
J 0
(-575 3075);
DISPLAY INVISIBLE (-575 3075);
FORCEPROP 1 LAST BODY_TYPE PLUMBING
J 2
(-575 3125);
DISPLAY 0.872340 (-575 3125);
PAINT GREEN (-575 3125);
DISPLAY INVISIBLE (-575 3125);
FORCEPROP 1 LAST HDL_TAP TRUE
J 2
(-900 2950);
DISPLAY 0.872340 (-900 2950);
DISPLAY INVISIBLE (-900 2950);
FORCEPROP 1 LAST PATH I170
J 2
(-573 3075);
DISPLAY 0.872340 (-573 3075);
PAINT GREEN (-573 3075);
DISPLAY INVISIBLE (-573 3075);
FORCEADD TAP..1
R 2
(-400 1775);
FORCEPROP 3 LASTPIN (-350 1775) SIG_NAME UPI_CPU1_CPU0_P1P0_DP<10>
J 0
(-340 1785);
DISPLAY 0.659574 (-340 1785);
PAINT MONO (-340 1785);
DISPLAY INVISIBLE (-340 1785);
FORCEPROP 1 LASTPIN (-350 1775) BN 10
J 2
(-338 1783);
DISPLAY 0.680851 (-338 1783);
PAINT GREEN (-338 1783);
FORCEPROP 2 LAST CDS_LIB standard
J 0
(-400 1775);
DISPLAY INVISIBLE (-400 1775);
FORCEPROP 1 LAST BODY_TYPE PLUMBING
J 2
(-400 1825);
DISPLAY 0.872340 (-400 1825);
PAINT GREEN (-400 1825);
DISPLAY INVISIBLE (-400 1825);
FORCEPROP 1 LAST HDL_TAP TRUE
J 2
(-725 1650);
DISPLAY 0.872340 (-725 1650);
DISPLAY INVISIBLE (-725 1650);
FORCEPROP 1 LAST PATH I171
J 2
(-398 1775);
DISPLAY 0.872340 (-398 1775);
PAINT GREEN (-398 1775);
DISPLAY INVISIBLE (-398 1775);
FORCEADD TAP..1
R 2
(-400 1825);
FORCEPROP 3 LASTPIN (-350 1825) SIG_NAME UPI_CPU1_CPU0_P1P0_DP<11>
J 0
(-340 1835);
DISPLAY 0.659574 (-340 1835);
PAINT MONO (-340 1835);
DISPLAY INVISIBLE (-340 1835);
FORCEPROP 1 LASTPIN (-350 1825) BN 11
J 2
(-338 1833);
DISPLAY 0.680851 (-338 1833);
PAINT GREEN (-338 1833);
FORCEPROP 2 LAST CDS_LIB standard
J 0
(-400 1825);
DISPLAY INVISIBLE (-400 1825);
FORCEPROP 1 LAST BODY_TYPE PLUMBING
J 2
(-400 1875);
DISPLAY 0.872340 (-400 1875);
PAINT GREEN (-400 1875);
DISPLAY INVISIBLE (-400 1875);
FORCEPROP 1 LAST HDL_TAP TRUE
J 2
(-725 1700);
DISPLAY 0.872340 (-725 1700);
DISPLAY INVISIBLE (-725 1700);
FORCEPROP 1 LAST PATH I172
J 2
(-398 1825);
DISPLAY 0.872340 (-398 1825);
PAINT GREEN (-398 1825);
DISPLAY INVISIBLE (-398 1825);
FORCEADD TAP..1
R 2
(-400 1425);
FORCEPROP 3 LASTPIN (-350 1425) SIG_NAME UPI_CPU1_CPU0_P1P0_DP<3>
J 0
(-340 1435);
DISPLAY 0.659574 (-340 1435);
PAINT MONO (-340 1435);
DISPLAY INVISIBLE (-340 1435);
FORCEPROP 1 LASTPIN (-350 1425) BN 3
J 2
(-338 1433);
DISPLAY 0.680851 (-338 1433);
PAINT GREEN (-338 1433);
FORCEPROP 2 LAST CDS_LIB standard
J 0
(-400 1425);
DISPLAY INVISIBLE (-400 1425);
FORCEPROP 1 LAST BODY_TYPE PLUMBING
J 2
(-400 1475);
DISPLAY 0.872340 (-400 1475);
PAINT GREEN (-400 1475);
DISPLAY INVISIBLE (-400 1475);
FORCEPROP 1 LAST HDL_TAP TRUE
J 2
(-725 1300);
DISPLAY 0.872340 (-725 1300);
DISPLAY INVISIBLE (-725 1300);
FORCEPROP 1 LAST PATH I173
J 2
(-398 1425);
DISPLAY 0.872340 (-398 1425);
PAINT GREEN (-398 1425);
DISPLAY INVISIBLE (-398 1425);
FORCEADD TAP..1
R 2
(-400 1525);
FORCEPROP 3 LASTPIN (-350 1525) SIG_NAME UPI_CPU1_CPU0_P1P0_DP<5>
J 0
(-340 1535);
DISPLAY 0.659574 (-340 1535);
PAINT MONO (-340 1535);
DISPLAY INVISIBLE (-340 1535);
FORCEPROP 1 LASTPIN (-350 1525) BN 5
J 2
(-338 1533);
DISPLAY 0.680851 (-338 1533);
PAINT GREEN (-338 1533);
FORCEPROP 2 LAST CDS_LIB standard
J 0
(-400 1525);
DISPLAY INVISIBLE (-400 1525);
FORCEPROP 1 LAST BODY_TYPE PLUMBING
J 2
(-400 1575);
DISPLAY 0.872340 (-400 1575);
PAINT GREEN (-400 1575);
DISPLAY INVISIBLE (-400 1575);
FORCEPROP 1 LAST HDL_TAP TRUE
J 2
(-725 1400);
DISPLAY 0.872340 (-725 1400);
DISPLAY INVISIBLE (-725 1400);
FORCEPROP 1 LAST PATH I174
J 2
(-398 1525);
DISPLAY 0.872340 (-398 1525);
PAINT GREEN (-398 1525);
DISPLAY INVISIBLE (-398 1525);
FORCEADD TAP..1
R 2
(-575 2675);
FORCEPROP 3 LASTPIN (-525 2675) SIG_NAME UPI_CPU1_CPU0_P1P0_DN<3>
J 0
(-515 2685);
DISPLAY 0.659574 (-515 2685);
PAINT MONO (-515 2685);
DISPLAY INVISIBLE (-515 2685);
FORCEPROP 1 LASTPIN (-525 2675) BN 3
J 2
(-513 2683);
DISPLAY 0.680851 (-513 2683);
PAINT GREEN (-513 2683);
FORCEPROP 2 LAST CDS_LIB standard
J 0
(-575 2675);
DISPLAY INVISIBLE (-575 2675);
FORCEPROP 1 LAST BODY_TYPE PLUMBING
J 2
(-575 2725);
DISPLAY 0.872340 (-575 2725);
PAINT GREEN (-575 2725);
DISPLAY INVISIBLE (-575 2725);
FORCEPROP 1 LAST HDL_TAP TRUE
J 2
(-900 2550);
DISPLAY 0.872340 (-900 2550);
DISPLAY INVISIBLE (-900 2550);
FORCEPROP 1 LAST PATH I175
J 2
(-573 2675);
DISPLAY 0.872340 (-573 2675);
PAINT GREEN (-573 2675);
DISPLAY INVISIBLE (-573 2675);
FORCEADD TAP..1
R 2
(-575 2775);
FORCEPROP 3 LASTPIN (-525 2775) SIG_NAME UPI_CPU1_CPU0_P1P0_DN<5>
J 0
(-515 2785);
DISPLAY 0.659574 (-515 2785);
PAINT MONO (-515 2785);
DISPLAY INVISIBLE (-515 2785);
FORCEPROP 1 LASTPIN (-525 2775) BN 5
J 2
(-513 2783);
DISPLAY 0.680851 (-513 2783);
PAINT GREEN (-513 2783);
FORCEPROP 2 LAST CDS_LIB standard
J 0
(-575 2775);
DISPLAY INVISIBLE (-575 2775);
FORCEPROP 1 LAST BODY_TYPE PLUMBING
J 2
(-575 2825);
DISPLAY 0.872340 (-575 2825);
PAINT GREEN (-575 2825);
DISPLAY INVISIBLE (-575 2825);
FORCEPROP 1 LAST HDL_TAP TRUE
J 2
(-900 2650);
DISPLAY 0.872340 (-900 2650);
DISPLAY INVISIBLE (-900 2650);
FORCEPROP 1 LAST PATH I176
J 2
(-573 2775);
DISPLAY 0.872340 (-573 2775);
PAINT GREEN (-573 2775);
DISPLAY INVISIBLE (-573 2775);
FORCEADD TAP..1
R 2
(-400 2975);
FORCEPROP 3 LASTPIN (-350 2975) SIG_NAME UPI_CPU1_CPU0_P1P0_DP<9>
J 0
(-340 2985);
DISPLAY 0.659574 (-340 2985);
PAINT MONO (-340 2985);
DISPLAY INVISIBLE (-340 2985);
FORCEPROP 1 LASTPIN (-350 2975) BN 9
J 2
(-338 2983);
DISPLAY 0.680851 (-338 2983);
PAINT GREEN (-338 2983);
FORCEPROP 2 LAST CDS_LIB standard
J 0
(-400 2975);
DISPLAY INVISIBLE (-400 2975);
FORCEPROP 1 LAST BODY_TYPE PLUMBING
J 2
(-400 3025);
DISPLAY 0.872340 (-400 3025);
PAINT GREEN (-400 3025);
DISPLAY INVISIBLE (-400 3025);
FORCEPROP 1 LAST HDL_TAP TRUE
J 2
(-725 2850);
DISPLAY 0.872340 (-725 2850);
DISPLAY INVISIBLE (-725 2850);
FORCEPROP 1 LAST PATH I19
J 2
(-398 2975);
DISPLAY 0.872340 (-398 2975);
PAINT GREEN (-398 2975);
DISPLAY INVISIBLE (-398 2975);
FORCEADD OFFPAGE..1
(-1800 3775);
FORCEPROP 2 LAST $XR0 64 
J 0
(-2051 3775);
DISPLAY 0.638298 (-2051 3775);
PAINT MONO (-2051 3775);
FORCEPROP 2 LAST CDS_LIB standard
J 0
(-1800 3775);
PAINT MONO (-1800 3775);
DISPLAY INVISIBLE (-1800 3775);
FORCEPROP 1 LAST OFFPAGE TRUE
J 0
(-1475 3650);
DISPLAY 0.872340 (-1475 3650);
DISPLAY INVISIBLE (-1475 3650);
FORCEPROP 1 LAST COMMENT_BODY TRUE
J 0
(-1675 3675);
DISPLAY 0.872340 (-1675 3675);
PAINT GREEN (-1675 3675);
DISPLAY INVISIBLE (-1675 3675);
FORCEPROP 2 LAST PATH I2
J 0
(-1750 3850);
DISPLAY 1.021277 (-1750 3850);
DISPLAY INVISIBLE (-1750 3850);
FORCEADD TAP..1
R 2
(-400 2925);
FORCEPROP 3 LASTPIN (-350 2925) SIG_NAME UPI_CPU1_CPU0_P1P0_DP<8>
J 0
(-340 2935);
DISPLAY 0.659574 (-340 2935);
PAINT MONO (-340 2935);
DISPLAY INVISIBLE (-340 2935);
FORCEPROP 1 LASTPIN (-350 2925) BN 8
J 2
(-338 2933);
DISPLAY 0.680851 (-338 2933);
PAINT GREEN (-338 2933);
FORCEPROP 2 LAST CDS_LIB standard
J 0
(-400 2925);
DISPLAY INVISIBLE (-400 2925);
FORCEPROP 1 LAST BODY_TYPE PLUMBING
J 2
(-400 2975);
DISPLAY 0.872340 (-400 2975);
PAINT GREEN (-400 2975);
DISPLAY INVISIBLE (-400 2975);
FORCEPROP 1 LAST HDL_TAP TRUE
J 2
(-725 2800);
DISPLAY 0.872340 (-725 2800);
DISPLAY INVISIBLE (-725 2800);
FORCEPROP 1 LAST PATH I21
J 2
(-398 2925);
DISPLAY 0.872340 (-398 2925);
PAINT GREEN (-398 2925);
DISPLAY INVISIBLE (-398 2925);
FORCEADD TAP..1
R 2
(-400 3625);
FORCEPROP 3 LASTPIN (-350 3625) SIG_NAME UPI_CPU1_CPU0_P1P0_DP<22>
J 0
(-340 3635);
DISPLAY 0.659574 (-340 3635);
PAINT MONO (-340 3635);
DISPLAY INVISIBLE (-340 3635);
FORCEPROP 1 LASTPIN (-350 3625) BN 22
J 2
(-338 3633);
DISPLAY 0.680851 (-338 3633);
PAINT GREEN (-338 3633);
FORCEPROP 2 LAST CDS_LIB standard
J 0
(-400 3625);
DISPLAY INVISIBLE (-400 3625);
FORCEPROP 1 LAST BODY_TYPE PLUMBING
J 2
(-400 3675);
DISPLAY 0.872340 (-400 3675);
PAINT GREEN (-400 3675);
DISPLAY INVISIBLE (-400 3675);
FORCEPROP 1 LAST HDL_TAP TRUE
J 2
(-725 3500);
DISPLAY 0.872340 (-725 3500);
DISPLAY INVISIBLE (-725 3500);
FORCEPROP 1 LAST PATH I34
J 2
(-398 3625);
DISPLAY 0.872340 (-398 3625);
PAINT GREEN (-398 3625);
DISPLAY INVISIBLE (-398 3625);
FORCEADD TAP..1
(2975 2925);
FORCEPROP 3 LASTPIN (2925 2925) SIG_NAME UPI_CPU0_CPU1_P0P1_DP<8>
J 0
(2935 2935);
DISPLAY 0.659574 (2935 2935);
PAINT MONO (2935 2935);
DISPLAY INVISIBLE (2935 2935);
FORCEPROP 1 LASTPIN (2925 2925) BN 8
J 0
(2913 2933);
DISPLAY 0.680851 (2913 2933);
PAINT GREEN (2913 2933);
FORCEPROP 2 LAST CDS_LIB standard
J 0
(2975 2925);
PAINT MONO (2975 2925);
DISPLAY INVISIBLE (2975 2925);
FORCEPROP 1 LAST BODY_TYPE PLUMBING
J 0
(2975 2975);
DISPLAY 0.872340 (2975 2975);
PAINT GREEN (2975 2975);
DISPLAY INVISIBLE (2975 2975);
FORCEPROP 1 LAST HDL_TAP TRUE
J 0
(3300 2800);
DISPLAY 0.872340 (3300 2800);
DISPLAY INVISIBLE (3300 2800);
FORCEPROP 1 LAST PATH I52
J 0
(2973 2925);
DISPLAY 0.872340 (2973 2925);
PAINT GREEN (2973 2925);
DISPLAY INVISIBLE (2973 2925);
FORCEADD TAP..1
(2975 2975);
FORCEPROP 3 LASTPIN (2925 2975) SIG_NAME UPI_CPU0_CPU1_P0P1_DP<9>
J 0
(2935 2985);
DISPLAY 0.659574 (2935 2985);
PAINT MONO (2935 2985);
DISPLAY INVISIBLE (2935 2985);
FORCEPROP 1 LASTPIN (2925 2975) BN 9
J 0
(2913 2983);
DISPLAY 0.680851 (2913 2983);
PAINT GREEN (2913 2983);
FORCEPROP 2 LAST CDS_LIB standard
J 0
(2975 2975);
PAINT MONO (2975 2975);
DISPLAY INVISIBLE (2975 2975);
FORCEPROP 1 LAST BODY_TYPE PLUMBING
J 0
(2975 3025);
DISPLAY 0.872340 (2975 3025);
PAINT GREEN (2975 3025);
DISPLAY INVISIBLE (2975 3025);
FORCEPROP 1 LAST HDL_TAP TRUE
J 0
(3300 2850);
DISPLAY 0.872340 (3300 2850);
DISPLAY INVISIBLE (3300 2850);
FORCEPROP 1 LAST PATH I53
J 0
(2973 2975);
DISPLAY 0.872340 (2973 2975);
PAINT GREEN (2973 2975);
DISPLAY INVISIBLE (2973 2975);
FORCEADD TAP..1
(2975 3075);
FORCEPROP 3 LASTPIN (2925 3075) SIG_NAME UPI_CPU0_CPU1_P0P1_DP<11>
J 0
(2935 3085);
DISPLAY 0.659574 (2935 3085);
PAINT MONO (2935 3085);
DISPLAY INVISIBLE (2935 3085);
FORCEPROP 1 LASTPIN (2925 3075) BN 11
J 0
(2913 3083);
DISPLAY 0.680851 (2913 3083);
PAINT GREEN (2913 3083);
FORCEPROP 2 LAST CDS_LIB standard
J 0
(2975 3075);
PAINT MONO (2975 3075);
DISPLAY INVISIBLE (2975 3075);
FORCEPROP 1 LAST BODY_TYPE PLUMBING
J 0
(2975 3125);
DISPLAY 0.872340 (2975 3125);
PAINT GREEN (2975 3125);
DISPLAY INVISIBLE (2975 3125);
FORCEPROP 1 LAST HDL_TAP TRUE
J 0
(3300 2950);
DISPLAY 0.872340 (3300 2950);
DISPLAY INVISIBLE (3300 2950);
FORCEPROP 1 LAST PATH I54
J 0
(2973 3075);
DISPLAY 0.872340 (2973 3075);
PAINT GREEN (2973 3075);
DISPLAY INVISIBLE (2973 3075);
FORCEADD TAP..1
(2975 3025);
FORCEPROP 3 LASTPIN (2925 3025) SIG_NAME UPI_CPU0_CPU1_P0P1_DP<10>
J 0
(2935 3035);
DISPLAY 0.659574 (2935 3035);
PAINT MONO (2935 3035);
DISPLAY INVISIBLE (2935 3035);
FORCEPROP 1 LASTPIN (2925 3025) BN 10
J 0
(2913 3033);
DISPLAY 0.680851 (2913 3033);
PAINT GREEN (2913 3033);
FORCEPROP 2 LAST CDS_LIB standard
J 0
(2975 3025);
PAINT MONO (2975 3025);
DISPLAY INVISIBLE (2975 3025);
FORCEPROP 1 LAST BODY_TYPE PLUMBING
J 0
(2975 3075);
DISPLAY 0.872340 (2975 3075);
PAINT GREEN (2975 3075);
DISPLAY INVISIBLE (2975 3075);
FORCEPROP 1 LAST HDL_TAP TRUE
J 0
(3300 2900);
DISPLAY 0.872340 (3300 2900);
DISPLAY INVISIBLE (3300 2900);
FORCEPROP 1 LAST PATH I55
J 0
(2973 3025);
DISPLAY 0.872340 (2973 3025);
PAINT GREEN (2973 3025);
DISPLAY INVISIBLE (2973 3025);
FORCEADD TAP..1
(2975 3225);
FORCEPROP 3 LASTPIN (2925 3225) SIG_NAME UPI_CPU0_CPU1_P0P1_DP<14>
J 0
(2935 3235);
DISPLAY 0.659574 (2935 3235);
PAINT MONO (2935 3235);
DISPLAY INVISIBLE (2935 3235);
FORCEPROP 1 LASTPIN (2925 3225) BN 14
J 0
(2913 3233);
DISPLAY 0.680851 (2913 3233);
PAINT GREEN (2913 3233);
FORCEPROP 2 LAST CDS_LIB standard
J 0
(2975 3225);
PAINT MONO (2975 3225);
DISPLAY INVISIBLE (2975 3225);
FORCEPROP 1 LAST BODY_TYPE PLUMBING
J 0
(2975 3275);
DISPLAY 0.872340 (2975 3275);
PAINT GREEN (2975 3275);
DISPLAY INVISIBLE (2975 3275);
FORCEPROP 1 LAST HDL_TAP TRUE
J 0
(3300 3100);
DISPLAY 0.872340 (3300 3100);
DISPLAY INVISIBLE (3300 3100);
FORCEPROP 1 LAST PATH I58
J 0
(2973 3225);
DISPLAY 0.872340 (2973 3225);
PAINT GREEN (2973 3225);
DISPLAY INVISIBLE (2973 3225);
FORCEADD TAP..1
(2975 3325);
FORCEPROP 3 LASTPIN (2925 3325) SIG_NAME UPI_CPU0_CPU1_P0P1_DP<16>
J 0
(2935 3335);
DISPLAY 0.659574 (2935 3335);
PAINT MONO (2935 3335);
DISPLAY INVISIBLE (2935 3335);
FORCEPROP 1 LASTPIN (2925 3325) BN 16
J 0
(2913 3333);
DISPLAY 0.680851 (2913 3333);
PAINT GREEN (2913 3333);
FORCEPROP 2 LAST CDS_LIB standard
J 0
(2975 3325);
PAINT MONO (2975 3325);
DISPLAY INVISIBLE (2975 3325);
FORCEPROP 1 LAST BODY_TYPE PLUMBING
J 0
(2975 3375);
DISPLAY 0.872340 (2975 3375);
PAINT GREEN (2975 3375);
DISPLAY INVISIBLE (2975 3375);
FORCEPROP 1 LAST HDL_TAP TRUE
J 0
(3300 3200);
DISPLAY 0.872340 (3300 3200);
DISPLAY INVISIBLE (3300 3200);
FORCEPROP 1 LAST PATH I59
J 0
(2973 3325);
DISPLAY 0.872340 (2973 3325);
PAINT GREEN (2973 3325);
DISPLAY INVISIBLE (2973 3325);
FORCEADD TAP..1
(2975 3375);
FORCEPROP 3 LASTPIN (2925 3375) SIG_NAME UPI_CPU0_CPU1_P0P1_DP<17>
J 0
(2935 3385);
DISPLAY 0.659574 (2935 3385);
PAINT MONO (2935 3385);
DISPLAY INVISIBLE (2935 3385);
FORCEPROP 1 LASTPIN (2925 3375) BN 17
J 0
(2913 3383);
DISPLAY 0.680851 (2913 3383);
PAINT GREEN (2913 3383);
FORCEPROP 2 LAST CDS_LIB standard
J 0
(2975 3375);
DISPLAY INVISIBLE (2975 3375);
FORCEPROP 1 LAST BODY_TYPE PLUMBING
J 0
(2975 3425);
DISPLAY 0.872340 (2975 3425);
PAINT GREEN (2975 3425);
DISPLAY INVISIBLE (2975 3425);
FORCEPROP 1 LAST HDL_TAP TRUE
J 0
(3300 3250);
DISPLAY 0.872340 (3300 3250);
DISPLAY INVISIBLE (3300 3250);
FORCEPROP 1 LAST PATH I61
J 0
(2973 3375);
DISPLAY 0.872340 (2973 3375);
PAINT GREEN (2973 3375);
DISPLAY INVISIBLE (2973 3375);
FORCEADD TAP..1
(2975 3425);
FORCEPROP 3 LASTPIN (2925 3425) SIG_NAME UPI_CPU0_CPU1_P0P1_DP<18>
J 0
(2935 3435);
DISPLAY 0.659574 (2935 3435);
PAINT MONO (2935 3435);
DISPLAY INVISIBLE (2935 3435);
FORCEPROP 1 LASTPIN (2925 3425) BN 18
J 0
(2913 3433);
DISPLAY 0.680851 (2913 3433);
PAINT GREEN (2913 3433);
FORCEPROP 2 LAST CDS_LIB standard
J 0
(2975 3425);
DISPLAY INVISIBLE (2975 3425);
FORCEPROP 1 LAST BODY_TYPE PLUMBING
J 0
(2975 3475);
DISPLAY 0.872340 (2975 3475);
PAINT GREEN (2975 3475);
DISPLAY INVISIBLE (2975 3475);
FORCEPROP 1 LAST HDL_TAP TRUE
J 0
(3300 3300);
DISPLAY 0.872340 (3300 3300);
DISPLAY INVISIBLE (3300 3300);
FORCEPROP 1 LAST PATH I62
J 0
(2973 3425);
DISPLAY 0.872340 (2973 3425);
PAINT GREEN (2973 3425);
DISPLAY INVISIBLE (2973 3425);
FORCEADD TAP..1
(2975 3475);
FORCEPROP 3 LASTPIN (2925 3475) SIG_NAME UPI_CPU0_CPU1_P0P1_DP<19>
J 0
(2935 3485);
DISPLAY 0.659574 (2935 3485);
PAINT MONO (2935 3485);
DISPLAY INVISIBLE (2935 3485);
FORCEPROP 1 LASTPIN (2925 3475) BN 19
J 0
(2913 3483);
DISPLAY 0.680851 (2913 3483);
PAINT GREEN (2913 3483);
FORCEPROP 2 LAST CDS_LIB standard
J 0
(2975 3475);
DISPLAY INVISIBLE (2975 3475);
FORCEPROP 1 LAST BODY_TYPE PLUMBING
J 0
(2975 3525);
DISPLAY 0.872340 (2975 3525);
PAINT GREEN (2975 3525);
DISPLAY INVISIBLE (2975 3525);
FORCEPROP 1 LAST HDL_TAP TRUE
J 0
(3300 3350);
DISPLAY 0.872340 (3300 3350);
DISPLAY INVISIBLE (3300 3350);
FORCEPROP 1 LAST PATH I64
J 0
(2973 3475);
DISPLAY 0.872340 (2973 3475);
PAINT GREEN (2973 3475);
DISPLAY INVISIBLE (2973 3475);
FORCEADD TAP..1
(2975 3675);
FORCEPROP 3 LASTPIN (2925 3675) SIG_NAME UPI_CPU0_CPU1_P0P1_DP<23>
J 0
(2935 3685);
DISPLAY 0.659574 (2935 3685);
PAINT MONO (2935 3685);
DISPLAY INVISIBLE (2935 3685);
FORCEPROP 1 LASTPIN (2925 3675) BN 23
J 0
(2913 3683);
DISPLAY 0.680851 (2913 3683);
PAINT GREEN (2913 3683);
FORCEPROP 2 LAST CDS_LIB standard
J 0
(2975 3675);
DISPLAY INVISIBLE (2975 3675);
FORCEPROP 1 LAST BODY_TYPE PLUMBING
J 0
(2975 3725);
DISPLAY 0.872340 (2975 3725);
PAINT GREEN (2975 3725);
DISPLAY INVISIBLE (2975 3725);
FORCEPROP 1 LAST HDL_TAP TRUE
J 0
(3300 3550);
DISPLAY 0.872340 (3300 3550);
DISPLAY INVISIBLE (3300 3550);
FORCEPROP 1 LAST PATH I66
J 0
(2973 3675);
DISPLAY 0.872340 (2973 3675);
PAINT GREEN (2973 3675);
DISPLAY INVISIBLE (2973 3675);
FORCEADD OFFPAGE..2
(4175 3700);
FORCEPROP 2 LAST $XR0 64 
J 0
(4364 3700);
DISPLAY 0.638298 (4364 3700);
PAINT MONO (4364 3700);
FORCEPROP 2 LAST CDS_LIB standard
J 0
(4175 3700);
PAINT MONO (4175 3700);
DISPLAY INVISIBLE (4175 3700);
FORCEPROP 1 LAST OFFPAGE TRUE
J 0
(4500 3575);
DISPLAY 1.170213 (4500 3575);
PAINT GREEN (4500 3575);
DISPLAY INVISIBLE (4500 3575);
FORCEPROP 1 LAST COMMENT_BODY TRUE
J 0
(4130 3605);
DISPLAY 1.170213 (4130 3605);
PAINT GREEN (4130 3605);
DISPLAY INVISIBLE (4130 3605);
FORCEPROP 2 LAST PATH I69
J 0
(4350 3775);
DISPLAY 1.021277 (4350 3775);
DISPLAY INVISIBLE (4350 3775);
FORCEADD SOCKET4677_AZIF0045P001C01CS..22
(1300 2475);
FORCEPROP 1 LAST PART_NUMBER DGA^7000023
J 0
(250 3925);
DISPLAY 0.723404 (250 3925);
PAINT GREEN (250 3925);
DISPLAY INVISIBLE (250 3925);
FORCEPROP 2 LAST VALUE SOCKET4677_AZIF0045-P001C01CS
J 0
(250 4050);
DISPLAY 1.021277 (250 4050);
FORCEPROP 1 LAST MATERIAL IO
J 0
(250 3850);
DISPLAY 0.723404 (250 3850);
PAINT GREEN (250 3850);
FORCEPROP 2 LAST PART_TYPE SMLF
J 0
(250 4100);
DISPLAY 1.021277 (250 4100);
FORCEPROP 1 LAST $LOCATION U2
J 0
(250 4000);
DISPLAY 0.723404 (250 4000);
PAINT GREEN (250 4000);
FORCEPROP 0 LASTPIN (100 1275) $PN K6
J 2
(90 1285);
DISPLAY 0.680851 (90 1285);
PAINT MONO (90 1285);
FORCEPROP 0 LASTPIN (100 1325) $PN N5
J 2
(90 1335);
DISPLAY 0.680851 (90 1335);
PAINT MONO (90 1335);
FORCEPROP 0 LASTPIN (100 1375) $PN P6
J 2
(90 1385);
DISPLAY 0.680851 (90 1385);
PAINT MONO (90 1385);
FORCEPROP 0 LASTPIN (100 1425) $PN U5
J 2
(90 1435);
DISPLAY 0.680851 (90 1435);
PAINT MONO (90 1435);
FORCEPROP 0 LASTPIN (100 1475) $PN V6
J 2
(90 1485);
DISPLAY 0.680851 (90 1485);
PAINT MONO (90 1485);
FORCEPROP 0 LASTPIN (100 1525) $PN AA5
J 2
(90 1535);
DISPLAY 0.680851 (90 1535);
PAINT MONO (90 1535);
FORCEPROP 0 LASTPIN (100 1575) $PN AB6
J 2
(90 1585);
DISPLAY 0.680851 (90 1585);
PAINT MONO (90 1585);
FORCEPROP 0 LASTPIN (100 1625) $PN AE5
J 2
(90 1635);
DISPLAY 0.680851 (90 1635);
PAINT MONO (90 1635);
FORCEPROP 0 LASTPIN (100 1675) $PN AF6
J 2
(90 1685);
DISPLAY 0.680851 (90 1685);
PAINT MONO (90 1685);
FORCEPROP 0 LASTPIN (100 1725) $PN AH6
J 2
(90 1735);
DISPLAY 0.680851 (90 1735);
PAINT MONO (90 1735);
FORCEPROP 0 LASTPIN (100 1775) $PN AK6
J 2
(90 1785);
DISPLAY 0.680851 (90 1785);
PAINT MONO (90 1785);
FORCEPROP 0 LASTPIN (100 1825) $PN AN5
J 2
(90 1835);
DISPLAY 0.680851 (90 1835);
PAINT MONO (90 1835);
FORCEPROP 0 LASTPIN (100 1875) $PN AP6
J 2
(90 1885);
DISPLAY 0.680851 (90 1885);
PAINT MONO (90 1885);
FORCEPROP 0 LASTPIN (100 1925) $PN AU5
J 2
(90 1935);
DISPLAY 0.680851 (90 1935);
PAINT MONO (90 1935);
FORCEPROP 0 LASTPIN (100 1975) $PN AV6
J 2
(90 1985);
DISPLAY 0.680851 (90 1985);
PAINT MONO (90 1985);
FORCEPROP 0 LASTPIN (100 2025) $PN BA5
J 2
(90 2035);
DISPLAY 0.680851 (90 2035);
PAINT MONO (90 2035);
FORCEPROP 0 LASTPIN (100 2075) $PN BB6
J 2
(90 2085);
DISPLAY 0.680851 (90 2085);
PAINT MONO (90 2085);
FORCEPROP 0 LASTPIN (100 2125) $PN BE5
J 2
(90 2135);
DISPLAY 0.680851 (90 2135);
PAINT MONO (90 2135);
FORCEPROP 0 LASTPIN (100 2175) $PN BF6
J 2
(90 2185);
DISPLAY 0.680851 (90 2185);
PAINT MONO (90 2185);
FORCEPROP 0 LASTPIN (100 2225) $PN BJ5
J 2
(90 2235);
DISPLAY 0.680851 (90 2235);
PAINT MONO (90 2235);
FORCEPROP 0 LASTPIN (100 2275) $PN BK6
J 2
(90 2285);
DISPLAY 0.680851 (90 2285);
PAINT MONO (90 2285);
FORCEPROP 0 LASTPIN (100 2325) $PN BN5
J 2
(90 2335);
DISPLAY 0.680851 (90 2335);
PAINT MONO (90 2335);
FORCEPROP 0 LASTPIN (100 2375) $PN BR7
J 2
(90 2385);
DISPLAY 0.680851 (90 2385);
PAINT MONO (90 2385);
FORCEPROP 0 LASTPIN (100 2425) $PN BU5
J 2
(90 2435);
DISPLAY 0.680851 (90 2435);
PAINT MONO (90 2435);
FORCEPROP 0 LASTPIN (100 2525) $PN L7
J 2
(90 2535);
DISPLAY 0.680851 (90 2535);
PAINT MONO (90 2535);
FORCEPROP 0 LASTPIN (100 2575) $PN M6
J 2
(90 2585);
DISPLAY 0.680851 (90 2585);
PAINT MONO (90 2585);
FORCEPROP 0 LASTPIN (100 2625) $PN R7
J 2
(90 2635);
DISPLAY 0.680851 (90 2635);
PAINT MONO (90 2635);
FORCEPROP 0 LASTPIN (100 2675) $PN T6
J 2
(90 2685);
DISPLAY 0.680851 (90 2685);
PAINT MONO (90 2685);
FORCEPROP 0 LASTPIN (100 2725) $PN W7
J 2
(90 2735);
DISPLAY 0.680851 (90 2735);
PAINT MONO (90 2735);
FORCEPROP 0 LASTPIN (100 2775) $PN Y6
J 2
(90 2785);
DISPLAY 0.680851 (90 2785);
PAINT MONO (90 2785);
FORCEPROP 0 LASTPIN (100 2825) $PN AC7
J 2
(90 2835);
DISPLAY 0.680851 (90 2835);
PAINT MONO (90 2835);
FORCEPROP 0 LASTPIN (100 2875) $PN AD6
J 2
(90 2885);
DISPLAY 0.680851 (90 2885);
PAINT MONO (90 2885);
FORCEPROP 0 LASTPIN (100 2925) $PN AG7
J 2
(90 2935);
DISPLAY 0.680851 (90 2935);
PAINT MONO (90 2935);
FORCEPROP 0 LASTPIN (100 2975) $PN AJ5
J 2
(90 2985);
DISPLAY 0.680851 (90 2985);
PAINT MONO (90 2985);
FORCEPROP 0 LASTPIN (100 3025) $PN AL7
J 2
(90 3035);
DISPLAY 0.680851 (90 3035);
PAINT MONO (90 3035);
FORCEPROP 0 LASTPIN (100 3075) $PN AM6
J 2
(90 3085);
DISPLAY 0.680851 (90 3085);
PAINT MONO (90 3085);
FORCEPROP 0 LASTPIN (100 3125) $PN AR7
J 2
(90 3135);
DISPLAY 0.680851 (90 3135);
PAINT MONO (90 3135);
FORCEPROP 0 LASTPIN (100 3175) $PN AT6
J 2
(90 3185);
DISPLAY 0.680851 (90 3185);
PAINT MONO (90 3185);
FORCEPROP 0 LASTPIN (100 3225) $PN AW7
J 2
(90 3235);
DISPLAY 0.680851 (90 3235);
PAINT MONO (90 3235);
FORCEPROP 0 LASTPIN (100 3275) $PN AY6
J 2
(90 3285);
DISPLAY 0.680851 (90 3285);
PAINT MONO (90 3285);
FORCEPROP 0 LASTPIN (100 3325) $PN BC7
J 2
(90 3335);
DISPLAY 0.680851 (90 3335);
PAINT MONO (90 3335);
FORCEPROP 0 LASTPIN (100 3375) $PN BD6
J 2
(90 3385);
DISPLAY 0.680851 (90 3385);
PAINT MONO (90 3385);
FORCEPROP 0 LASTPIN (100 3425) $PN BG7
J 2
(90 3435);
DISPLAY 0.680851 (90 3435);
PAINT MONO (90 3435);
FORCEPROP 0 LASTPIN (100 3475) $PN BH6
J 2
(90 3485);
DISPLAY 0.680851 (90 3485);
PAINT MONO (90 3485);
FORCEPROP 0 LASTPIN (100 3525) $PN BL7
J 2
(90 3535);
DISPLAY 0.680851 (90 3535);
PAINT MONO (90 3535);
FORCEPROP 0 LASTPIN (100 3575) $PN BM6
J 2
(90 3585);
DISPLAY 0.680851 (90 3585);
PAINT MONO (90 3585);
FORCEPROP 0 LASTPIN (100 3625) $PN BP6
J 2
(90 3635);
DISPLAY 0.680851 (90 3635);
PAINT MONO (90 3635);
FORCEPROP 0 LASTPIN (100 3675) $PN BT6
J 2
(90 3685);
DISPLAY 0.680851 (90 3685);
PAINT MONO (90 3685);
FORCEPROP 0 LASTPIN (2500 1275) $PN K4
J 0
(2510 1285);
DISPLAY 0.680851 (2510 1285);
PAINT MONO (2510 1285);
FORCEPROP 0 LASTPIN (2500 1325) $PN M2
J 0
(2510 1335);
DISPLAY 0.680851 (2510 1335);
PAINT MONO (2510 1335);
FORCEPROP 0 LASTPIN (2500 1375) $PN N1
J 0
(2510 1385);
DISPLAY 0.680851 (2510 1385);
PAINT MONO (2510 1385);
FORCEPROP 0 LASTPIN (2500 1425) $PN T2
J 0
(2510 1435);
DISPLAY 0.680851 (2510 1435);
PAINT MONO (2510 1435);
FORCEPROP 0 LASTPIN (2500 1475) $PN U1
J 0
(2510 1485);
DISPLAY 0.680851 (2510 1485);
PAINT MONO (2510 1485);
FORCEPROP 0 LASTPIN (2500 1525) $PN Y2
J 0
(2510 1535);
DISPLAY 0.680851 (2510 1535);
PAINT MONO (2510 1535);
FORCEPROP 0 LASTPIN (2500 1575) $PN AA1
J 0
(2510 1585);
DISPLAY 0.680851 (2510 1585);
PAINT MONO (2510 1585);
FORCEPROP 0 LASTPIN (2500 1625) $PN AD2
J 0
(2510 1635);
DISPLAY 0.680851 (2510 1635);
PAINT MONO (2510 1635);
FORCEPROP 0 LASTPIN (2500 1675) $PN AF2
J 0
(2510 1685);
DISPLAY 0.680851 (2510 1685);
PAINT MONO (2510 1685);
FORCEPROP 0 LASTPIN (2500 1725) $PN AH2
J 0
(2510 1735);
DISPLAY 0.680851 (2510 1735);
PAINT MONO (2510 1735);
FORCEPROP 0 LASTPIN (2500 1775) $PN AK2
J 0
(2510 1785);
DISPLAY 0.680851 (2510 1785);
PAINT MONO (2510 1785);
FORCEPROP 0 LASTPIN (2500 1825) $PN AM2
J 0
(2510 1835);
DISPLAY 0.680851 (2510 1835);
PAINT MONO (2510 1835);
FORCEPROP 0 LASTPIN (2500 1875) $PN AP2
J 0
(2510 1885);
DISPLAY 0.680851 (2510 1885);
PAINT MONO (2510 1885);
FORCEPROP 0 LASTPIN (2500 1925) $PN AT2
J 0
(2510 1935);
DISPLAY 0.680851 (2510 1935);
PAINT MONO (2510 1935);
FORCEPROP 0 LASTPIN (2500 1975) $PN AU1
J 0
(2510 1985);
DISPLAY 0.680851 (2510 1985);
PAINT MONO (2510 1985);
FORCEPROP 0 LASTPIN (2500 2025) $PN AY2
J 0
(2510 2035);
DISPLAY 0.680851 (2510 2035);
PAINT MONO (2510 2035);
FORCEPROP 0 LASTPIN (2500 2075) $PN BB2
J 0
(2510 2085);
DISPLAY 0.680851 (2510 2085);
PAINT MONO (2510 2085);
FORCEPROP 0 LASTPIN (2500 2125) $PN BD2
J 0
(2510 2135);
DISPLAY 0.680851 (2510 2135);
PAINT MONO (2510 2135);
FORCEPROP 0 LASTPIN (2500 2175) $PN BF2
J 0
(2510 2185);
DISPLAY 0.680851 (2510 2185);
PAINT MONO (2510 2185);
FORCEPROP 0 LASTPIN (2500 2225) $PN BH2
J 0
(2510 2235);
DISPLAY 0.680851 (2510 2235);
PAINT MONO (2510 2235);
FORCEPROP 0 LASTPIN (2500 2275) $PN BK2
J 0
(2510 2285);
DISPLAY 0.680851 (2510 2285);
PAINT MONO (2510 2285);
FORCEPROP 0 LASTPIN (2500 2325) $PN BM2
J 0
(2510 2335);
DISPLAY 0.680851 (2510 2335);
PAINT MONO (2510 2335);
FORCEPROP 0 LASTPIN (2500 2375) $PN BR3
J 0
(2510 2385);
DISPLAY 0.680851 (2510 2385);
PAINT MONO (2510 2385);
FORCEPROP 0 LASTPIN (2500 2425) $PN BT2
J 0
(2510 2435);
DISPLAY 0.680851 (2510 2435);
PAINT MONO (2510 2435);
FORCEPROP 0 LASTPIN (2500 2525) $PN J3
J 0
(2510 2535);
DISPLAY 0.680851 (2510 2535);
PAINT MONO (2510 2535);
FORCEPROP 0 LASTPIN (2500 2575) $PN L3
J 0
(2510 2585);
DISPLAY 0.680851 (2510 2585);
PAINT MONO (2510 2585);
FORCEPROP 0 LASTPIN (2500 2625) $PN P2
J 0
(2510 2635);
DISPLAY 0.680851 (2510 2635);
PAINT MONO (2510 2635);
FORCEPROP 0 LASTPIN (2500 2675) $PN R3
J 0
(2510 2685);
DISPLAY 0.680851 (2510 2685);
PAINT MONO (2510 2685);
FORCEPROP 0 LASTPIN (2500 2725) $PN V2
J 0
(2510 2735);
DISPLAY 0.680851 (2510 2735);
PAINT MONO (2510 2735);
FORCEPROP 0 LASTPIN (2500 2775) $PN W3
J 0
(2510 2785);
DISPLAY 0.680851 (2510 2785);
PAINT MONO (2510 2785);
FORCEPROP 0 LASTPIN (2500 2825) $PN AB2
J 0
(2510 2835);
DISPLAY 0.680851 (2510 2835);
PAINT MONO (2510 2835);
FORCEPROP 0 LASTPIN (2500 2875) $PN AC3
J 0
(2510 2885);
DISPLAY 0.680851 (2510 2885);
PAINT MONO (2510 2885);
FORCEPROP 0 LASTPIN (2500 2925) $PN AE1
J 0
(2510 2935);
DISPLAY 0.680851 (2510 2935);
PAINT MONO (2510 2935);
FORCEPROP 0 LASTPIN (2500 2975) $PN AG3
J 0
(2510 2985);
DISPLAY 0.680851 (2510 2985);
PAINT MONO (2510 2985);
FORCEPROP 0 LASTPIN (2500 3025) $PN AJ1
J 0
(2510 3035);
DISPLAY 0.680851 (2510 3035);
PAINT MONO (2510 3035);
FORCEPROP 0 LASTPIN (2500 3075) $PN AL3
J 0
(2510 3085);
DISPLAY 0.680851 (2510 3085);
PAINT MONO (2510 3085);
FORCEPROP 0 LASTPIN (2500 3125) $PN AN1
J 0
(2510 3135);
DISPLAY 0.680851 (2510 3135);
PAINT MONO (2510 3135);
FORCEPROP 0 LASTPIN (2500 3175) $PN AR3
J 0
(2510 3185);
DISPLAY 0.680851 (2510 3185);
PAINT MONO (2510 3185);
FORCEPROP 0 LASTPIN (2500 3225) $PN AV2
J 0
(2510 3235);
DISPLAY 0.680851 (2510 3235);
PAINT MONO (2510 3235);
FORCEPROP 0 LASTPIN (2500 3275) $PN AW3
J 0
(2510 3285);
DISPLAY 0.680851 (2510 3285);
PAINT MONO (2510 3285);
FORCEPROP 0 LASTPIN (2500 3325) $PN BA1
J 0
(2510 3335);
DISPLAY 0.680851 (2510 3335);
PAINT MONO (2510 3335);
FORCEPROP 0 LASTPIN (2500 3375) $PN BC3
J 0
(2510 3385);
DISPLAY 0.680851 (2510 3385);
PAINT MONO (2510 3385);
FORCEPROP 0 LASTPIN (2500 3425) $PN BE1
J 0
(2510 3435);
DISPLAY 0.680851 (2510 3435);
PAINT MONO (2510 3435);
FORCEPROP 0 LASTPIN (2500 3475) $PN BG3
J 0
(2510 3485);
DISPLAY 0.680851 (2510 3485);
PAINT MONO (2510 3485);
FORCEPROP 0 LASTPIN (2500 3525) $PN BJ1
J 0
(2510 3535);
DISPLAY 0.680851 (2510 3535);
PAINT MONO (2510 3535);
FORCEPROP 0 LASTPIN (2500 3575) $PN BL3
J 0
(2510 3585);
DISPLAY 0.680851 (2510 3585);
PAINT MONO (2510 3585);
FORCEPROP 0 LASTPIN (2500 3625) $PN BN3
J 0
(2510 3635);
DISPLAY 0.680851 (2510 3635);
PAINT MONO (2510 3635);
FORCEPROP 0 LASTPIN (2500 3675) $PN BU3
J 0
(2510 3685);
DISPLAY 0.680851 (2510 3685);
PAINT MONO (2510 3685);
FORCEPROP 1 LAST CDS_LMAN_SYM_OUTLINE -1050,1350,1050,-1350
J 0
(1300 2475);
DISPLAY 0.468085 (1300 2475);
PAINT GREEN (1300 2475);
DISPLAY INVISIBLE (1300 2475);
FORCEPROP 1 LAST NEEDS_NO_SIZE TRUE
J 0
(1300 2475);
DISPLAY 0.723404 (1300 2475);
PAINT GREEN (1300 2475);
DISPLAY INVISIBLE (1300 2475);
FORCEPROP 2 LAST CDS_LIB pure_quanta
J 0
(1300 2475);
DISPLAY INVISIBLE (1300 2475);
FORCEPROP 2 LAST CDS_LOCATION U2
J 0
(250 4150);
DISPLAY 1.021277 (250 4150);
DISPLAY INVISIBLE (250 4150);
FORCEPROP 0 LAST $SEC 22
J 0
(250 4150);
DISPLAY 0.680851 (250 4150);
PAINT MONO (250 4150);
DISPLAY INVISIBLE (250 4150);
FORCEPROP 2 LAST CDS_SEC 22
J 0
(250 4150);
DISPLAY 1.021277 (250 4150);
DISPLAY INVISIBLE (250 4150);
FORCEPROP 1 LAST PATH I70
J 0
(1300 2475);
DISPLAY 0.723404 (1300 2475);
PAINT GREEN (1300 2475);
DISPLAY INVISIBLE (1300 2475);
FORCEADD TAP..1
R 2
(-575 1725);
FORCEPROP 3 LASTPIN (-525 1725) SIG_NAME UPI_CPU1_CPU0_P1P0_DN<9>
J 0
(-515 1735);
DISPLAY 0.659574 (-515 1735);
PAINT MONO (-515 1735);
DISPLAY INVISIBLE (-515 1735);
FORCEPROP 1 LASTPIN (-525 1725) BN 9
J 2
(-513 1733);
DISPLAY 0.680851 (-513 1733);
PAINT GREEN (-513 1733);
FORCEPROP 2 LAST CDS_LIB standard
J 0
(-575 1725);
DISPLAY INVISIBLE (-575 1725);
FORCEPROP 1 LAST BODY_TYPE PLUMBING
J 2
(-575 1775);
DISPLAY 0.872340 (-575 1775);
PAINT GREEN (-575 1775);
DISPLAY INVISIBLE (-575 1775);
FORCEPROP 1 LAST HDL_TAP TRUE
J 2
(-900 1600);
DISPLAY 0.872340 (-900 1600);
DISPLAY INVISIBLE (-900 1600);
FORCEPROP 1 LAST PATH I77
J 2
(-573 1725);
DISPLAY 0.872340 (-573 1725);
PAINT GREEN (-573 1725);
DISPLAY INVISIBLE (-573 1725);
FORCEADD TAP..1
R 2
(-575 1675);
FORCEPROP 3 LASTPIN (-525 1675) SIG_NAME UPI_CPU1_CPU0_P1P0_DN<8>
J 0
(-515 1685);
DISPLAY 0.659574 (-515 1685);
PAINT MONO (-515 1685);
DISPLAY INVISIBLE (-515 1685);
FORCEPROP 1 LASTPIN (-525 1675) BN 8
J 2
(-513 1683);
DISPLAY 0.680851 (-513 1683);
PAINT GREEN (-513 1683);
FORCEPROP 2 LAST CDS_LIB standard
J 0
(-575 1675);
DISPLAY INVISIBLE (-575 1675);
FORCEPROP 1 LAST BODY_TYPE PLUMBING
J 2
(-575 1725);
DISPLAY 0.872340 (-575 1725);
PAINT GREEN (-575 1725);
DISPLAY INVISIBLE (-575 1725);
FORCEPROP 1 LAST HDL_TAP TRUE
J 2
(-900 1550);
DISPLAY 0.872340 (-900 1550);
DISPLAY INVISIBLE (-900 1550);
FORCEPROP 1 LAST PATH I78
J 2
(-573 1675);
DISPLAY 0.872340 (-573 1675);
PAINT GREEN (-573 1675);
DISPLAY INVISIBLE (-573 1675);
FORCEADD TAP..1
R 2
(-575 1625);
FORCEPROP 3 LASTPIN (-525 1625) SIG_NAME UPI_CPU1_CPU0_P1P0_DN<7>
J 0
(-515 1635);
DISPLAY 0.659574 (-515 1635);
PAINT MONO (-515 1635);
DISPLAY INVISIBLE (-515 1635);
FORCEPROP 1 LASTPIN (-525 1625) BN 7
J 2
(-513 1633);
DISPLAY 0.680851 (-513 1633);
PAINT GREEN (-513 1633);
FORCEPROP 2 LAST CDS_LIB standard
J 0
(-575 1625);
DISPLAY INVISIBLE (-575 1625);
FORCEPROP 1 LAST BODY_TYPE PLUMBING
J 2
(-575 1675);
DISPLAY 0.872340 (-575 1675);
PAINT GREEN (-575 1675);
DISPLAY INVISIBLE (-575 1675);
FORCEPROP 1 LAST HDL_TAP TRUE
J 2
(-900 1500);
DISPLAY 0.872340 (-900 1500);
DISPLAY INVISIBLE (-900 1500);
FORCEPROP 1 LAST PATH I79
J 2
(-573 1625);
DISPLAY 0.872340 (-573 1625);
PAINT GREEN (-573 1625);
DISPLAY INVISIBLE (-573 1625);
FORCEADD TAP..1
R 2
(-575 1575);
FORCEPROP 3 LASTPIN (-525 1575) SIG_NAME UPI_CPU1_CPU0_P1P0_DN<6>
J 0
(-515 1585);
DISPLAY 0.659574 (-515 1585);
PAINT MONO (-515 1585);
DISPLAY INVISIBLE (-515 1585);
FORCEPROP 1 LASTPIN (-525 1575) BN 6
J 2
(-513 1583);
DISPLAY 0.680851 (-513 1583);
PAINT GREEN (-513 1583);
FORCEPROP 2 LAST CDS_LIB standard
J 0
(-575 1575);
DISPLAY INVISIBLE (-575 1575);
FORCEPROP 1 LAST BODY_TYPE PLUMBING
J 2
(-575 1625);
DISPLAY 0.872340 (-575 1625);
PAINT GREEN (-575 1625);
DISPLAY INVISIBLE (-575 1625);
FORCEPROP 1 LAST HDL_TAP TRUE
J 2
(-900 1450);
DISPLAY 0.872340 (-900 1450);
DISPLAY INVISIBLE (-900 1450);
FORCEPROP 1 LAST PATH I80
J 2
(-573 1575);
DISPLAY 0.872340 (-573 1575);
PAINT GREEN (-573 1575);
DISPLAY INVISIBLE (-573 1575);
FORCEADD TAP..1
R 2
(-575 1475);
FORCEPROP 3 LASTPIN (-525 1475) SIG_NAME UPI_CPU1_CPU0_P1P0_DN<4>
J 0
(-515 1485);
DISPLAY 0.659574 (-515 1485);
PAINT MONO (-515 1485);
DISPLAY INVISIBLE (-515 1485);
FORCEPROP 1 LASTPIN (-525 1475) BN 4
J 2
(-513 1483);
DISPLAY 0.680851 (-513 1483);
PAINT GREEN (-513 1483);
FORCEPROP 2 LAST CDS_LIB standard
J 0
(-575 1475);
DISPLAY INVISIBLE (-575 1475);
FORCEPROP 1 LAST BODY_TYPE PLUMBING
J 2
(-575 1525);
DISPLAY 0.872340 (-575 1525);
PAINT GREEN (-575 1525);
DISPLAY INVISIBLE (-575 1525);
FORCEPROP 1 LAST HDL_TAP TRUE
J 2
(-900 1350);
DISPLAY 0.872340 (-900 1350);
DISPLAY INVISIBLE (-900 1350);
FORCEPROP 1 LAST PATH I82
J 2
(-573 1475);
DISPLAY 0.872340 (-573 1475);
PAINT GREEN (-573 1475);
DISPLAY INVISIBLE (-573 1475);
FORCEADD TAP..1
R 2
(-575 1275);
FORCEPROP 3 LASTPIN (-525 1275) SIG_NAME UPI_CPU1_CPU0_P1P0_DN<0>
J 0
(-515 1285);
DISPLAY 0.659574 (-515 1285);
PAINT MONO (-515 1285);
DISPLAY INVISIBLE (-515 1285);
FORCEPROP 1 LASTPIN (-525 1275) BN 0
J 2
(-513 1283);
DISPLAY 0.680851 (-513 1283);
PAINT GREEN (-513 1283);
FORCEPROP 2 LAST CDS_LIB standard
J 0
(-575 1275);
DISPLAY INVISIBLE (-575 1275);
FORCEPROP 1 LAST BODY_TYPE PLUMBING
J 2
(-575 1325);
DISPLAY 0.872340 (-575 1325);
PAINT GREEN (-575 1325);
DISPLAY INVISIBLE (-575 1325);
FORCEPROP 1 LAST HDL_TAP TRUE
J 2
(-900 1150);
DISPLAY 0.872340 (-900 1150);
DISPLAY INVISIBLE (-900 1150);
FORCEPROP 1 LAST PATH I84
J 2
(-573 1275);
DISPLAY 0.872340 (-573 1275);
PAINT GREEN (-573 1275);
DISPLAY INVISIBLE (-573 1275);
FORCEADD TAP..1
R 2
(-575 1325);
FORCEPROP 3 LASTPIN (-525 1325) SIG_NAME UPI_CPU1_CPU0_P1P0_DN<1>
J 0
(-515 1335);
DISPLAY 0.659574 (-515 1335);
PAINT MONO (-515 1335);
DISPLAY INVISIBLE (-515 1335);
FORCEPROP 1 LASTPIN (-525 1325) BN 1
J 2
(-513 1333);
DISPLAY 0.680851 (-513 1333);
PAINT GREEN (-513 1333);
FORCEPROP 2 LAST CDS_LIB standard
J 0
(-575 1325);
DISPLAY INVISIBLE (-575 1325);
FORCEPROP 1 LAST BODY_TYPE PLUMBING
J 2
(-575 1375);
DISPLAY 0.872340 (-575 1375);
PAINT GREEN (-575 1375);
DISPLAY INVISIBLE (-575 1375);
FORCEPROP 1 LAST HDL_TAP TRUE
J 2
(-900 1200);
DISPLAY 0.872340 (-900 1200);
DISPLAY INVISIBLE (-900 1200);
FORCEPROP 1 LAST PATH I85
J 2
(-573 1325);
DISPLAY 0.872340 (-573 1325);
PAINT GREEN (-573 1325);
DISPLAY INVISIBLE (-573 1325);
FORCEADD TAP..1
R 2
(-575 1375);
FORCEPROP 3 LASTPIN (-525 1375) SIG_NAME UPI_CPU1_CPU0_P1P0_DN<2>
J 0
(-515 1385);
DISPLAY 0.659574 (-515 1385);
PAINT MONO (-515 1385);
DISPLAY INVISIBLE (-515 1385);
FORCEPROP 1 LASTPIN (-525 1375) BN 2
J 2
(-513 1383);
DISPLAY 0.680851 (-513 1383);
PAINT GREEN (-513 1383);
FORCEPROP 2 LAST CDS_LIB standard
J 0
(-575 1375);
DISPLAY INVISIBLE (-575 1375);
FORCEPROP 1 LAST BODY_TYPE PLUMBING
J 2
(-575 1425);
DISPLAY 0.872340 (-575 1425);
PAINT GREEN (-575 1425);
DISPLAY INVISIBLE (-575 1425);
FORCEPROP 1 LAST HDL_TAP TRUE
J 2
(-900 1250);
DISPLAY 0.872340 (-900 1250);
DISPLAY INVISIBLE (-900 1250);
FORCEPROP 1 LAST PATH I86
J 2
(-573 1375);
DISPLAY 0.872340 (-573 1375);
PAINT GREEN (-573 1375);
DISPLAY INVISIBLE (-573 1375);
FORCEADD TAP..1
R 2
(-575 2375);
FORCEPROP 3 LASTPIN (-525 2375) SIG_NAME UPI_CPU1_CPU0_P1P0_DN<22>
J 0
(-515 2385);
DISPLAY 0.659574 (-515 2385);
PAINT MONO (-515 2385);
DISPLAY INVISIBLE (-515 2385);
FORCEPROP 1 LASTPIN (-525 2375) BN 22
J 2
(-513 2383);
DISPLAY 0.680851 (-513 2383);
PAINT GREEN (-513 2383);
FORCEPROP 2 LAST CDS_LIB standard
J 0
(-575 2375);
PAINT MONO (-575 2375);
DISPLAY INVISIBLE (-575 2375);
FORCEPROP 1 LAST BODY_TYPE PLUMBING
J 2
(-575 2425);
DISPLAY 0.872340 (-575 2425);
PAINT GREEN (-575 2425);
DISPLAY INVISIBLE (-575 2425);
FORCEPROP 1 LAST HDL_TAP TRUE
J 2
(-900 2250);
DISPLAY 0.872340 (-900 2250);
DISPLAY INVISIBLE (-900 2250);
FORCEPROP 1 LAST PATH I95
J 2
(-573 2375);
DISPLAY 0.872340 (-573 2375);
PAINT GREEN (-573 2375);
DISPLAY INVISIBLE (-573 2375);
FORCEADD TAP..1
R 2
(-400 2575);
FORCEPROP 3 LASTPIN (-350 2575) SIG_NAME UPI_CPU1_CPU0_P1P0_DP<1>
J 0
(-340 2585);
DISPLAY 0.659574 (-340 2585);
PAINT MONO (-340 2585);
DISPLAY INVISIBLE (-340 2585);
FORCEPROP 1 LASTPIN (-350 2575) BN 1
J 2
(-338 2583);
DISPLAY 0.680851 (-338 2583);
PAINT GREEN (-338 2583);
FORCEPROP 2 LAST CDS_LIB standard
J 0
(-400 2575);
DISPLAY INVISIBLE (-400 2575);
FORCEPROP 1 LAST BODY_TYPE PLUMBING
J 2
(-400 2625);
DISPLAY 0.872340 (-400 2625);
PAINT GREEN (-400 2625);
DISPLAY INVISIBLE (-400 2625);
FORCEPROP 1 LAST HDL_TAP TRUE
J 2
(-725 2450);
DISPLAY 0.872340 (-725 2450);
DISPLAY INVISIBLE (-725 2450);
FORCEPROP 1 LAST PATH I97
J 2
(-398 2575);
DISPLAY 0.872340 (-398 2575);
PAINT GREEN (-398 2575);
DISPLAY INVISIBLE (-398 2575);
FORCEADD TAP..1
R 2
(-400 2625);
FORCEPROP 3 LASTPIN (-350 2625) SIG_NAME UPI_CPU1_CPU0_P1P0_DP<2>
J 0
(-340 2635);
DISPLAY 0.659574 (-340 2635);
PAINT MONO (-340 2635);
DISPLAY INVISIBLE (-340 2635);
FORCEPROP 1 LASTPIN (-350 2625) BN 2
J 2
(-338 2633);
DISPLAY 0.680851 (-338 2633);
PAINT GREEN (-338 2633);
FORCEPROP 2 LAST CDS_LIB standard
J 0
(-400 2625);
DISPLAY INVISIBLE (-400 2625);
FORCEPROP 1 LAST BODY_TYPE PLUMBING
J 2
(-400 2675);
DISPLAY 0.872340 (-400 2675);
PAINT GREEN (-400 2675);
DISPLAY INVISIBLE (-400 2675);
FORCEPROP 1 LAST HDL_TAP TRUE
J 2
(-725 2500);
DISPLAY 0.872340 (-725 2500);
DISPLAY INVISIBLE (-725 2500);
FORCEPROP 1 LAST PATH I98
J 2
(-398 2625);
DISPLAY 0.872340 (-398 2625);
PAINT GREEN (-398 2625);
DISPLAY INVISIBLE (-398 2625);
FORCEADD DESIGN_NOTE..1
(4100 3175);
FORCEPROP 0 LAST S1 DP/DN SWAP
J 0
(3900 3025);
DISPLAY 1.021277 (3900 3025);
PAINT SKYBLUE (3900 3025);
FORCEPROP 2 LAST CDS_LIB logical_power
J 0
(4100 3175);
DISPLAY INVISIBLE (4100 3175);
FORCEPROP 1 LAST COMMENT_BODY TRUE
J 0
(4125 3275);
DISPLAY 0.978723 (4125 3275);
DISPLAY INVISIBLE (4125 3275);
FORCEADD DESIGN_NOTE..1
(-1775 3175);
FORCEPROP 0 LAST S1 DP/DN SWAP
J 0
(-1975 3025);
DISPLAY 1.021277 (-1975 3025);
PAINT SKYBLUE (-1975 3025);
FORCEPROP 2 LAST CDS_LIB logical_power
J 0
(-1775 3175);
DISPLAY INVISIBLE (-1775 3175);
FORCEPROP 1 LAST COMMENT_BODY TRUE
J 0
(-1750 3275);
DISPLAY 0.978723 (-1750 3275);
DISPLAY INVISIBLE (-1750 3275);
FORCEADD QUANTA_TITLE_BLOCK_C..1
(5900 -1825);
FORCEPROP 0 LAST CDS_CON_LAST_MODIFIED Fri Aug 25 14:00:16 2023
J 0
(4015 -1810);
PAINT MONO (4015 -1810);
DISPLAY INVISIBLE (4015 -1810);
FORCEPROP 1 LAST CUSTOM_TXT_CDS <CON_LAST_MODIFIED>
J 0
(4015 -1810);
DISPLAY 0.978723 (4015 -1810);
FORCEPROP 2 LAST CUSTOM_TXT_CDS <XR_PAGE_TITLE>
J 0
(-1990 3425);
DISPLAY 0.638298 (-1990 3425);
PAINT PINK (-1990 3425);
DISPLAY INVISIBLE (-1990 3425);
FORCEPROP 2 LAST CUSTOM_TXT_CDS <Q_NUMBER>
J 0
(4497 -1722);
DISPLAY 1.212766 (4497 -1722);
FORCEPROP 1 LAST CUSTOM_TXT_CDS <NAME_2>
J 0
(2725 -1775);
FORCEPROP 1 LAST CUSTOM_TXT_CDS <NAME_1>
J 0
(2725 -1650);
FORCEPROP 1 LAST CUSTOM_TXT_CDS <Q_PROJ>
J 0
(3518 -1723);
DISPLAY 1.212766 (3518 -1723);
FORCEPROP 1 LAST CUSTOM_TXT_CDS <Q_REV>
J 0
(5716 -1722);
DISPLAY 1.212766 (5716 -1722);
FORCEPROP 1 LAST CUSTOM_TXT_CDS <CON_PAGE_NUM> OF <CON_TOTAL_PAGES>
J 0
(5454 -1807);
DISPLAY 0.978723 (5454 -1807);
FORCEPROP 1 LAST Q_TITLE SPR CPU0 - UPI0 (20 OF 30)
J 0
(-3466 -1799);
DISPLAY 1.957447 (-3466 -1799);
PAINT GREEN (-3466 -1799);
FORCEPROP 1 LAST Q_DEPT 
J 1
(2137 -1776);
DISPLAY 1.957447 (2137 -1776);
PAINT GREEN (2137 -1776);
FORCEPROP 2 LAST PAGE_BORDER TRUE
J 0
(-1990 3425);
DISPLAY 0.638298 (-1990 3425);
PAINT PINK (-1990 3425);
DISPLAY INVISIBLE (-1990 3425);
FORCEPROP 1 LAST CDS_LMAN_SYM_OUTLINE -9475,6775,100,-125
J 0
(5900 -1825);
DISPLAY 0.468085 (5900 -1825);
PAINT GREEN (5900 -1825);
DISPLAY INVISIBLE (5900 -1825);
FORCEPROP 2 LAST CDS_LIB pure_quanta
J 0
(5900 -1825);
PAINT MONO (5900 -1825);
DISPLAY INVISIBLE (5900 -1825);
FORCEPROP 2 LAST CDS_XR_PAGE_TITLE CR-32 : @S9S_MB_2U_LIB.S9S_MB_2U(SCH_1):PAGE32
J 0
(-1990 3425);
DISPLAY 0.638298 (-1990 3425);
PAINT PINK (-1990 3425);
DISPLAY INVISIBLE (-1990 3425);
FORCEPROP 1 LAST COMMENT_BODY TRUE
J 0
(5912 -1838);
DISPLAY 0.978723 (5912 -1838);
PAINT GREEN (5912 -1838);
DISPLAY INVISIBLE (5912 -1838);
WIRE 17 -1 (3025 2600)(3025 2550);
WIRE 17 -1 (3025 2600)(3025 2650);
WIRE 17 -1 (3025 2400)(3025 2550);
WIRE 17 -1 (3025 2350)(3025 2400);
WIRE 17 -1 (3025 2650)(3025 2700);
WIRE 17 -1 (3025 2700)(3025 2750);
WIRE 17 -1 (3025 2300)(3025 2350);
WIRE 17 -1 (3025 2050)(3025 2300);
WIRE 17 -1 (3025 2750)(3025 2800);
WIRE 17 -1 (3025 2800)(3025 2850);
WIRE 17 -1 (3025 1950)(3025 2050);
WIRE 17 -1 (3025 1900)(3025 1950);
WIRE 17 -1 (3025 2850)(3025 2900);
WIRE 17 -1 (3025 2900)(3025 2950);
WIRE 17 -1 (3025 2950)(3025 3000);
WIRE 17 -1 (3025 3000)(3025 3050);
WIRE 17 -1 (3025 3050)(3025 3100);
WIRE 17 -1 (3025 3250)(3025 3100);
WIRE 17 -1 (3025 3250)(3025 3350);
WIRE 17 -1 (3025 3350)(3025 3400);
WIRE 17 -1 (3025 3400)(3025 3450);
WIRE 17 -1 (3025 3450)(3025 3500);
WIRE 17 -1 (3025 3700)(3025 3500);
WIRE 17 -1 (3025 3700)(4125 3700);
FORCEPROP 2 LAST SIG_NAME UPI_CPU0_CPU1_P0P1_DP<23:0>
J 0
(3165 3710);
DISPLAY 0.680851 (3165 3710);
PAINT WHITE (3165 3710);
WIRE 17 -1 (3225 2500)(3225 3150);
WIRE 17 -1 (3225 2500)(4125 2500);
FORCEPROP 2 LAST SIG_NAME UPI_CPU0_CPU1_P0P1_DN<23:0>
J 0
(3265 2510);
DISPLAY 0.680851 (3265 2510);
PAINT WHITE (3265 2510);
WIRE 17 -1 (3225 3150)(3225 3200);
WIRE 17 -1 (3225 3200)(3225 3300);
WIRE 17 -1 (3225 3300)(3225 3550);
WIRE 17 -1 (3225 3550)(3225 3600);
WIRE 17 -1 (3225 3600)(3225 3650);
WIRE 17 -1 (3225 1300)(3225 1350);
WIRE 17 -1 (3225 1350)(3225 1400);
WIRE 17 -1 (3225 1400)(3225 1450);
WIRE 17 -1 (3225 1450)(3225 1500);
WIRE 17 -1 (3225 1500)(3225 1550);
WIRE 17 -1 (3225 1550)(3225 1600);
WIRE 17 -1 (3225 1600)(3225 1650);
WIRE 17 -1 (3225 1650)(3225 1700);
WIRE 17 -1 (3225 1750)(3225 1700);
WIRE 17 -1 (3225 1750)(3225 1800);
WIRE 17 -1 (3225 1800)(3225 1850);
WIRE 17 -1 (3225 1850)(3225 2000);
WIRE 17 -1 (3225 2000)(3225 2100);
WIRE 17 -1 (3225 2150)(3225 2100);
WIRE 17 -1 (3225 2200)(3225 2150);
WIRE 17 -1 (3225 2250)(3225 2200);
WIRE 17 -1 (3225 2250)(3225 2450);
WIRE 17 -1 (3225 2450)(3225 2500);
WIRE 17 -1 (-450 2550)(-450 2600);
WIRE 17 -1 (-450 2550)(-450 2450);
WIRE 17 -1 (-450 2600)(-450 2650);
WIRE 17 -1 (-450 2750)(-450 2650);
WIRE 17 -1 (-450 2450)(-450 2350);
WIRE 17 -1 (-450 2350)(-450 2300);
WIRE 17 -1 (-450 2850)(-450 2750);
WIRE 17 -1 (-450 2850)(-450 2900);
WIRE 17 -1 (-450 2300)(-450 2250);
WIRE 17 -1 (-450 2250)(-450 2200);
WIRE 17 -1 (-450 2900)(-450 2950);
WIRE 17 -1 (-450 2950)(-450 3000);
WIRE 17 -1 (-450 2200)(-450 2150);
WIRE 17 -1 (-450 2150)(-450 2100);
WIRE 17 -1 (-450 3650)(-450 3000);
WIRE 17 -1 (-450 3650)(-450 3775);
WIRE 17 -1 (-450 2100)(-450 2050);
WIRE 17 -1 (-450 2050)(-450 2000);
WIRE 17 -1 (-1750 3775)(-450 3775);
FORCEPROP 2 LAST SIG_NAME UPI_CPU1_CPU0_P1P0_DP<23:0>
J 0
(-1635 3785);
DISPLAY 0.680851 (-1635 3785);
PAINT WHITE (-1635 3785);
WIRE 17 -1 (-625 2800)(-625 2700);
WIRE 17 -1 (-625 3050)(-625 2800);
WIRE 17 -1 (-625 2700)(-625 2500);
WIRE 17 -1 (-625 2400)(-625 2500);
WIRE 17 -1 (-1750 2500)(-625 2500);
FORCEPROP 2 LAST SIG_NAME UPI_CPU1_CPU0_P1P0_DN<23:0>
J 0
(-1635 2510);
DISPLAY 0.680851 (-1635 2510);
PAINT WHITE (-1635 2510);
WIRE 17 -1 (-625 3100)(-625 3050);
WIRE 17 -1 (-625 3150)(-625 3100);
WIRE 17 -1 (-625 3200)(-625 3150);
WIRE 17 -1 (-625 3250)(-625 3200);
WIRE 17 -1 (-625 3300)(-625 3250);
WIRE 17 -1 (-625 3350)(-625 3300);
WIRE 17 -1 (-625 3400)(-625 3350);
WIRE 17 -1 (-625 3450)(-625 3400);
WIRE 17 -1 (-625 3500)(-625 3450);
WIRE 17 -1 (-625 3550)(-625 3500);
WIRE 17 -1 (-625 3550)(-625 3600);
WIRE 17 -1 (-625 3600)(-625 3700);
WIRE 17 -1 (-625 1300)(-625 1350);
WIRE 17 -1 (-625 1350)(-625 1400);
WIRE 17 -1 (-625 1500)(-625 1400);
WIRE 17 -1 (-625 1600)(-625 1500);
WIRE 17 -1 (-625 1600)(-625 1650);
WIRE 17 -1 (-625 1650)(-625 1700);
WIRE 17 -1 (-625 1700)(-625 1750);
WIRE 17 -1 (-625 1750)(-625 2400);
WIRE 17 -1 (-450 1550)(-450 1450);
WIRE 17 -1 (-450 1800)(-450 1550);
WIRE 17 -1 (-450 1850)(-450 1800);
WIRE 17 -1 (-450 1900)(-450 1850);
WIRE 17 -1 (-450 1950)(-450 1900);
WIRE 17 -1 (-450 2000)(-450 1950);
WIRE 16 -1 (-350 2425)(100 2425);
WIRE 16 -1 (-525 2375)(100 2375);
WIRE 16 -1 (-350 2325)(100 2325);
WIRE 16 -1 (-350 2275)(100 2275);
WIRE 16 -1 (-350 2225)(100 2225);
WIRE 16 -1 (-350 2175)(100 2175);
WIRE 16 -1 (-350 2125)(100 2125);
WIRE 16 -1 (-350 2075)(100 2075);
WIRE 16 -1 (-350 2025)(100 2025);
WIRE 16 -1 (-350 1975)(100 1975);
WIRE 16 -1 (-350 1925)(100 1925);
WIRE 16 -1 (-350 1875)(100 1875);
WIRE 16 -1 (-350 1825)(100 1825);
WIRE 16 -1 (-350 1775)(100 1775);
WIRE 16 -1 (-525 1725)(100 1725);
WIRE 16 -1 (-525 1675)(100 1675);
WIRE 16 -1 (-525 1625)(100 1625);
WIRE 16 -1 (-525 1575)(100 1575);
WIRE 16 -1 (-350 1525)(100 1525);
WIRE 16 -1 (-525 1475)(100 1475);
WIRE 16 -1 (-350 1425)(100 1425);
WIRE 16 -1 (-525 1375)(100 1375);
WIRE 16 -1 (-525 1325)(100 1325);
WIRE 16 -1 (-525 1275)(100 1275);
WIRE 16 -1 (100 3675)(-525 3675);
WIRE 16 -1 (-350 3625)(100 3625);
WIRE 16 -1 (100 3575)(-525 3575);
WIRE 16 -1 (100 3525)(-525 3525);
WIRE 16 -1 (100 3475)(-525 3475);
WIRE 16 -1 (-525 3425)(100 3425);
WIRE 16 -1 (-525 3375)(100 3375);
WIRE 16 -1 (100 3325)(-525 3325);
WIRE 16 -1 (-525 3275)(100 3275);
WIRE 16 -1 (-525 3225)(100 3225);
WIRE 16 -1 (100 3175)(-525 3175);
FORCEPROP 0 LAST $PNN UPI_CPU1_CPU0_P1P0_DP<13>
J 0
(-437 3175);
DISPLAY INVISIBLE (-437 3175);
WIRE 16 -1 (-525 3125)(100 3125);
FORCEPROP 0 LAST $PNN UPI_CPU1_CPU0_P1P0_DP<12>
J 0
(-437 3125);
DISPLAY INVISIBLE (-437 3125);
WIRE 16 -1 (-525 3075)(100 3075);
WIRE 16 -1 (100 3025)(-525 3025);
WIRE 16 -1 (-350 2975)(100 2975);
WIRE 16 -1 (-350 2925)(100 2925);
WIRE 16 -1 (-350 2875)(100 2875);
WIRE 16 -1 (-350 2825)(100 2825);
WIRE 16 -1 (-525 2775)(100 2775);
WIRE 16 -1 (-350 2725)(100 2725);
WIRE 16 -1 (-525 2675)(100 2675);
WIRE 16 -1 (-350 2625)(100 2625);
WIRE 16 -1 (-350 2575)(100 2575);
WIRE 16 -1 (-350 2525)(100 2525);
WIRE 16 -1 (2500 2425)(3125 2425);
WIRE 16 -1 (2500 2375)(2925 2375);
WIRE 16 -1 (2500 2325)(2925 2325);
WIRE 16 -1 (2500 2275)(2925 2275);
WIRE 16 -1 (2500 2225)(3125 2225);
WIRE 16 -1 (2500 2175)(3125 2175);
WIRE 16 -1 (2500 2125)(3125 2125);
WIRE 16 -1 (2500 2075)(3125 2075);
WIRE 16 -1 (2500 2025)(2925 2025);
WIRE 16 -1 (2500 1975)(3125 1975);
WIRE 16 -1 (2500 1925)(2925 1925);
WIRE 16 -1 (2500 1875)(2925 1875);
WIRE 16 -1 (2500 1825)(3125 1825);
WIRE 16 -1 (2500 1775)(3125 1775);
WIRE 16 -1 (2500 1725)(3125 1725);
WIRE 16 -1 (2500 1675)(3125 1675);
WIRE 16 -1 (2500 1625)(3125 1625);
WIRE 16 -1 (2500 1575)(3125 1575);
WIRE 16 -1 (2500 1525)(3125 1525);
WIRE 16 -1 (2500 1475)(3125 1475);
WIRE 16 -1 (2500 1425)(3125 1425);
WIRE 16 -1 (2500 1375)(3125 1375);
WIRE 16 -1 (2500 1325)(3125 1325);
WIRE 16 -1 (2500 1275)(3125 1275);
WIRE 16 -1 (2500 3675)(2925 3675);
WIRE 16 -1 (2500 3625)(3125 3625);
WIRE 16 -1 (2500 3575)(3125 3575);
WIRE 16 -1 (2500 3525)(3125 3525);
WIRE 16 -1 (2500 3475)(2925 3475);
WIRE 16 -1 (2500 3425)(2925 3425);
WIRE 16 -1 (2500 3375)(2925 3375);
WIRE 16 -1 (2500 3325)(2925 3325);
WIRE 16 -1 (2500 3275)(3125 3275);
WIRE 16 -1 (2500 3225)(2925 3225);
WIRE 16 -1 (2500 3175)(3125 3175);
WIRE 16 -1 (2500 3125)(3125 3125);
WIRE 16 -1 (2500 3075)(2925 3075);
WIRE 16 -1 (2500 3025)(2925 3025);
WIRE 16 -1 (2500 2975)(2925 2975);
WIRE 16 -1 (2500 2925)(2925 2925);
WIRE 16 -1 (2500 2875)(2925 2875);
WIRE 16 -1 (2500 2825)(2925 2825);
WIRE 16 -1 (2500 2775)(2925 2775);
WIRE 16 -1 (2500 2725)(2925 2725);
WIRE 16 -1 (2500 2675)(2925 2675);
WIRE 16 -1 (2500 2625)(2925 2625);
WIRE 16 -1 (2500 2575)(2925 2575);
WIRE 16 -1 (2500 2525)(2925 2525);
DOT 1 (3225 2500);
DOT 1 (-625 2500);
QUIT
